FILE_TYPE = MACRO_DRAWING;
SET COLOR_WIRE YELLOW;
SET COLOR_PROP MONO;
SET COLOR_DOT WHITE;
SET COLOR_ARC YELLOW;
SET COLOR_BODY GREEN;
SET COLOR_NOTE MONO;
SET PROP_DISPLAY VALUE;
SET PAGE_NUMBER P47;
FORCEADD OFFPAGE..3
(1600 5250);
FORCEPROP 2 LAST $XR0 25 
J 0
(1814 5250);
DISPLAY 0.638298 (1814 5250);
PAINT MONO (1814 5250);
FORCEPROP 2 LAST $XR1 48 
J 0
(1904 5250);
DISPLAY 0.638298 (1904 5250);
PAINT MONO (1904 5250);
FORCEPROP 2 LAST CDS_LIB mstr_standard
J 0
(1600 5250);
DISPLAY 0.787234 (1600 5250);
PAINT MONO (1600 5250);
DISPLAY INVISIBLE (1600 5250);
FORCEPROP 1 LAST OFFPAGE TRUE
J 0
(1925 5125);
DISPLAY 0.936170 (1925 5125);
PAINT GREEN (1925 5125);
DISPLAY INVISIBLE (1925 5125);
FORCEPROP 1 LAST COMMENT_BODY TRUE
J 0
(1550 5150);
DISPLAY 0.936170 (1550 5150);
PAINT GREEN (1550 5150);
DISPLAY INVISIBLE (1550 5150);
FORCEPROP 2 LAST PATH I1
J 0
(1800 5325);
DISPLAY 0.787234 (1800 5325);
PAINT MONO (1800 5325);
DISPLAY INVISIBLE (1800 5325);
FORCEADD TAP..6
R 2
(700 4900);
FORCEPROP 3 LASTPIN (650 4900) SIG_NAME M_C_DQS_DP<14>
J 0
(660 4910);
DISPLAY 0.659574 (660 4910);
PAINT MONO (660 4910);
DISPLAY INVISIBLE (660 4910);
FORCEPROP 1 LASTPIN (650 4900) BN 14
J 2
(700 4910);
DISPLAY 0.617021 (700 4910);
PAINT PINK (700 4910);
FORCEPROP 2 LAST CDS_LIB mstr_standard
J 0
(700 4900);
DISPLAY 0.787234 (700 4900);
PAINT MONO (700 4900);
DISPLAY INVISIBLE (700 4900);
FORCEPROP 1 LAST BODY_TYPE PLUMBING
J 2
(700 4850);
DISPLAY 1.234043 (700 4850);
PAINT GREEN (700 4850);
DISPLAY INVISIBLE (700 4850);
FORCEPROP 1 LAST HDL_TAP TRUE
J 2
(375 4775);
DISPLAY 1.234043 (375 4775);
PAINT GREEN (375 4775);
DISPLAY INVISIBLE (375 4775);
FORCEPROP 1 LAST PATH I10
J 2
(700 4900);
DISPLAY 0.936170 (700 4900);
PAINT GREEN (700 4900);
DISPLAY INVISIBLE (700 4900);
FORCEADD TAP..6
R 2
(-1700 1900);
FORCEPROP 3 LASTPIN (-1750 1900) SIG_NAME M_C_DQ<9>
J 0
(-1740 1910);
DISPLAY 0.659574 (-1740 1910);
PAINT MONO (-1740 1910);
DISPLAY INVISIBLE (-1740 1910);
FORCEPROP 1 LASTPIN (-1750 1900) BN 9
J 2
(-1700 1910);
DISPLAY 0.617021 (-1700 1910);
PAINT PINK (-1700 1910);
FORCEPROP 2 LAST CDS_LIB mstr_standard
J 2
(-1700 1900);
DISPLAY 0.787234 (-1700 1900);
PAINT MONO (-1700 1900);
DISPLAY INVISIBLE (-1700 1900);
FORCEPROP 1 LAST BODY_TYPE PLUMBING
J 2
(-1700 1850);
DISPLAY 1.234043 (-1700 1850);
PAINT GREEN (-1700 1850);
DISPLAY INVISIBLE (-1700 1850);
FORCEPROP 1 LAST HDL_TAP TRUE
J 2
(-2025 1775);
DISPLAY 1.234043 (-2025 1775);
PAINT GREEN (-2025 1775);
DISPLAY INVISIBLE (-2025 1775);
FORCEPROP 1 LAST PATH I100
J 2
(-1700 1900);
DISPLAY 0.936170 (-1700 1900);
PAINT GREEN (-1700 1900);
DISPLAY INVISIBLE (-1700 1900);
FORCEADD TAP..6
R 2
(-1700 2000);
FORCEPROP 3 LASTPIN (-1750 2000) SIG_NAME M_C_DQ<11>
J 0
(-1740 2010);
DISPLAY 0.659574 (-1740 2010);
PAINT MONO (-1740 2010);
DISPLAY INVISIBLE (-1740 2010);
FORCEPROP 1 LASTPIN (-1750 2000) BN 11
J 2
(-1700 2010);
DISPLAY 0.617021 (-1700 2010);
PAINT PINK (-1700 2010);
FORCEPROP 2 LAST CDS_LIB mstr_standard
J 2
(-1700 2000);
DISPLAY 0.787234 (-1700 2000);
PAINT MONO (-1700 2000);
DISPLAY INVISIBLE (-1700 2000);
FORCEPROP 1 LAST BODY_TYPE PLUMBING
J 2
(-1700 1950);
DISPLAY 1.234043 (-1700 1950);
PAINT GREEN (-1700 1950);
DISPLAY INVISIBLE (-1700 1950);
FORCEPROP 1 LAST HDL_TAP TRUE
J 2
(-2025 1875);
DISPLAY 1.234043 (-2025 1875);
PAINT GREEN (-2025 1875);
DISPLAY INVISIBLE (-2025 1875);
FORCEPROP 1 LAST PATH I101
J 2
(-1700 2000);
DISPLAY 0.936170 (-1700 2000);
PAINT GREEN (-1700 2000);
DISPLAY INVISIBLE (-1700 2000);
FORCEADD TAP..6
R 2
(-1700 1950);
FORCEPROP 3 LASTPIN (-1750 1950) SIG_NAME M_C_DQ<8>
J 0
(-1740 1960);
DISPLAY 0.659574 (-1740 1960);
PAINT MONO (-1740 1960);
DISPLAY INVISIBLE (-1740 1960);
FORCEPROP 1 LASTPIN (-1750 1950) BN 8
J 2
(-1700 1960);
DISPLAY 0.617021 (-1700 1960);
PAINT PINK (-1700 1960);
FORCEPROP 2 LAST CDS_LIB mstr_standard
J 2
(-1700 1950);
DISPLAY 0.787234 (-1700 1950);
PAINT MONO (-1700 1950);
DISPLAY INVISIBLE (-1700 1950);
FORCEPROP 1 LAST BODY_TYPE PLUMBING
J 2
(-1700 1900);
DISPLAY 1.234043 (-1700 1900);
PAINT GREEN (-1700 1900);
DISPLAY INVISIBLE (-1700 1900);
FORCEPROP 1 LAST HDL_TAP TRUE
J 2
(-2025 1825);
DISPLAY 1.234043 (-2025 1825);
PAINT GREEN (-2025 1825);
DISPLAY INVISIBLE (-2025 1825);
FORCEPROP 1 LAST PATH I102
J 2
(-1700 1950);
DISPLAY 0.936170 (-1700 1950);
PAINT GREEN (-1700 1950);
DISPLAY INVISIBLE (-1700 1950);
FORCEADD TAP..6
R 2
(-1700 1750);
FORCEPROP 3 LASTPIN (-1750 1750) SIG_NAME M_C_DQ<4>
J 0
(-1740 1760);
DISPLAY 0.659574 (-1740 1760);
PAINT MONO (-1740 1760);
DISPLAY INVISIBLE (-1740 1760);
FORCEPROP 1 LASTPIN (-1750 1750) BN 4
J 2
(-1700 1760);
DISPLAY 0.617021 (-1700 1760);
PAINT PINK (-1700 1760);
FORCEPROP 2 LAST CDS_LIB mstr_standard
J 2
(-1700 1750);
DISPLAY 0.787234 (-1700 1750);
PAINT MONO (-1700 1750);
DISPLAY INVISIBLE (-1700 1750);
FORCEPROP 1 LAST BODY_TYPE PLUMBING
J 2
(-1700 1700);
DISPLAY 1.234043 (-1700 1700);
PAINT GREEN (-1700 1700);
DISPLAY INVISIBLE (-1700 1700);
FORCEPROP 1 LAST HDL_TAP TRUE
J 2
(-2025 1625);
DISPLAY 1.234043 (-2025 1625);
PAINT GREEN (-2025 1625);
DISPLAY INVISIBLE (-2025 1625);
FORCEPROP 1 LAST PATH I103
J 2
(-1700 1750);
DISPLAY 0.936170 (-1700 1750);
PAINT GREEN (-1700 1750);
DISPLAY INVISIBLE (-1700 1750);
FORCEADD TAP..6
R 2
(-1700 1800);
FORCEPROP 3 LASTPIN (-1750 1800) SIG_NAME M_C_DQ<7>
J 0
(-1740 1810);
DISPLAY 0.659574 (-1740 1810);
PAINT MONO (-1740 1810);
DISPLAY INVISIBLE (-1740 1810);
FORCEPROP 1 LASTPIN (-1750 1800) BN 7
J 2
(-1700 1810);
DISPLAY 0.617021 (-1700 1810);
PAINT PINK (-1700 1810);
FORCEPROP 2 LAST CDS_LIB mstr_standard
J 2
(-1700 1800);
DISPLAY 0.787234 (-1700 1800);
PAINT MONO (-1700 1800);
DISPLAY INVISIBLE (-1700 1800);
FORCEPROP 1 LAST BODY_TYPE PLUMBING
J 2
(-1700 1750);
DISPLAY 1.234043 (-1700 1750);
PAINT GREEN (-1700 1750);
DISPLAY INVISIBLE (-1700 1750);
FORCEPROP 1 LAST HDL_TAP TRUE
J 2
(-2025 1675);
DISPLAY 1.234043 (-2025 1675);
PAINT GREEN (-2025 1675);
DISPLAY INVISIBLE (-2025 1675);
FORCEPROP 1 LAST PATH I104
J 2
(-1700 1800);
DISPLAY 0.936170 (-1700 1800);
PAINT GREEN (-1700 1800);
DISPLAY INVISIBLE (-1700 1800);
FORCEADD TAP..6
R 2
(-1700 1850);
FORCEPROP 3 LASTPIN (-1750 1850) SIG_NAME M_C_DQ<6>
J 0
(-1740 1860);
DISPLAY 0.659574 (-1740 1860);
PAINT MONO (-1740 1860);
DISPLAY INVISIBLE (-1740 1860);
FORCEPROP 1 LASTPIN (-1750 1850) BN 6
J 2
(-1700 1860);
DISPLAY 0.617021 (-1700 1860);
PAINT PINK (-1700 1860);
FORCEPROP 2 LAST CDS_LIB mstr_standard
J 2
(-1700 1850);
DISPLAY 0.787234 (-1700 1850);
PAINT MONO (-1700 1850);
DISPLAY INVISIBLE (-1700 1850);
FORCEPROP 1 LAST BODY_TYPE PLUMBING
J 2
(-1700 1800);
DISPLAY 1.234043 (-1700 1800);
PAINT GREEN (-1700 1800);
DISPLAY INVISIBLE (-1700 1800);
FORCEPROP 1 LAST HDL_TAP TRUE
J 2
(-2025 1725);
DISPLAY 1.234043 (-2025 1725);
PAINT GREEN (-2025 1725);
DISPLAY INVISIBLE (-2025 1725);
FORCEPROP 1 LAST PATH I105
J 2
(-1700 1850);
DISPLAY 0.936170 (-1700 1850);
PAINT GREEN (-1700 1850);
DISPLAY INVISIBLE (-1700 1850);
FORCEADD TAP..6
R 2
(-1700 1700);
FORCEPROP 3 LASTPIN (-1750 1700) SIG_NAME M_C_DQ<5>
J 0
(-1740 1710);
DISPLAY 0.659574 (-1740 1710);
PAINT MONO (-1740 1710);
DISPLAY INVISIBLE (-1740 1710);
FORCEPROP 1 LASTPIN (-1750 1700) BN 5
J 2
(-1700 1710);
DISPLAY 0.617021 (-1700 1710);
PAINT PINK (-1700 1710);
FORCEPROP 2 LAST CDS_LIB mstr_standard
J 2
(-1700 1700);
DISPLAY 0.787234 (-1700 1700);
PAINT MONO (-1700 1700);
DISPLAY INVISIBLE (-1700 1700);
FORCEPROP 1 LAST BODY_TYPE PLUMBING
J 2
(-1700 1650);
DISPLAY 1.234043 (-1700 1650);
PAINT GREEN (-1700 1650);
DISPLAY INVISIBLE (-1700 1650);
FORCEPROP 1 LAST HDL_TAP TRUE
J 2
(-2025 1575);
DISPLAY 1.234043 (-2025 1575);
PAINT GREEN (-2025 1575);
DISPLAY INVISIBLE (-2025 1575);
FORCEPROP 1 LAST PATH I106
J 2
(-1700 1700);
DISPLAY 0.936170 (-1700 1700);
PAINT GREEN (-1700 1700);
DISPLAY INVISIBLE (-1700 1700);
FORCEADD TAP..6
R 2
(-1700 1650);
FORCEPROP 3 LASTPIN (-1750 1650) SIG_NAME M_C_DQ<2>
J 0
(-1740 1660);
DISPLAY 0.659574 (-1740 1660);
PAINT MONO (-1740 1660);
DISPLAY INVISIBLE (-1740 1660);
FORCEPROP 1 LASTPIN (-1750 1650) BN 2
J 2
(-1700 1660);
DISPLAY 0.617021 (-1700 1660);
PAINT PINK (-1700 1660);
FORCEPROP 2 LAST CDS_LIB mstr_standard
J 2
(-1700 1650);
DISPLAY 0.787234 (-1700 1650);
PAINT MONO (-1700 1650);
DISPLAY INVISIBLE (-1700 1650);
FORCEPROP 1 LAST BODY_TYPE PLUMBING
J 2
(-1700 1600);
DISPLAY 1.234043 (-1700 1600);
PAINT GREEN (-1700 1600);
DISPLAY INVISIBLE (-1700 1600);
FORCEPROP 1 LAST HDL_TAP TRUE
J 2
(-2025 1525);
DISPLAY 1.234043 (-2025 1525);
PAINT GREEN (-2025 1525);
DISPLAY INVISIBLE (-2025 1525);
FORCEPROP 1 LAST PATH I107
J 2
(-1700 1650);
DISPLAY 0.936170 (-1700 1650);
PAINT GREEN (-1700 1650);
DISPLAY INVISIBLE (-1700 1650);
FORCEADD TAP..6
R 2
(-1700 1550);
FORCEPROP 3 LASTPIN (-1750 1550) SIG_NAME M_C_DQ<0>
J 0
(-1740 1560);
DISPLAY 0.659574 (-1740 1560);
PAINT MONO (-1740 1560);
DISPLAY INVISIBLE (-1740 1560);
FORCEPROP 1 LASTPIN (-1750 1550) BN 0
J 2
(-1700 1560);
DISPLAY 0.617021 (-1700 1560);
PAINT PINK (-1700 1560);
FORCEPROP 2 LAST CDS_LIB mstr_standard
J 2
(-1700 1550);
DISPLAY 0.787234 (-1700 1550);
PAINT MONO (-1700 1550);
DISPLAY INVISIBLE (-1700 1550);
FORCEPROP 1 LAST BODY_TYPE PLUMBING
J 2
(-1700 1500);
DISPLAY 1.234043 (-1700 1500);
PAINT GREEN (-1700 1500);
DISPLAY INVISIBLE (-1700 1500);
FORCEPROP 1 LAST HDL_TAP TRUE
J 2
(-2025 1425);
DISPLAY 1.234043 (-2025 1425);
PAINT GREEN (-2025 1425);
DISPLAY INVISIBLE (-2025 1425);
FORCEPROP 1 LAST PATH I108
J 2
(-1700 1550);
DISPLAY 0.936170 (-1700 1550);
PAINT GREEN (-1700 1550);
DISPLAY INVISIBLE (-1700 1550);
FORCEADD TAP..6
R 2
(-1700 1600);
FORCEPROP 3 LASTPIN (-1750 1600) SIG_NAME M_C_DQ<3>
J 0
(-1740 1610);
DISPLAY 0.659574 (-1740 1610);
PAINT MONO (-1740 1610);
DISPLAY INVISIBLE (-1740 1610);
FORCEPROP 1 LASTPIN (-1750 1600) BN 3
J 2
(-1700 1610);
DISPLAY 0.617021 (-1700 1610);
PAINT PINK (-1700 1610);
FORCEPROP 2 LAST CDS_LIB mstr_standard
J 2
(-1700 1600);
DISPLAY 0.787234 (-1700 1600);
PAINT MONO (-1700 1600);
DISPLAY INVISIBLE (-1700 1600);
FORCEPROP 1 LAST BODY_TYPE PLUMBING
J 2
(-1700 1550);
DISPLAY 1.234043 (-1700 1550);
PAINT GREEN (-1700 1550);
DISPLAY INVISIBLE (-1700 1550);
FORCEPROP 1 LAST HDL_TAP TRUE
J 2
(-2025 1475);
DISPLAY 1.234043 (-2025 1475);
PAINT GREEN (-2025 1475);
DISPLAY INVISIBLE (-2025 1475);
FORCEPROP 1 LAST PATH I109
J 2
(-1700 1600);
DISPLAY 0.936170 (-1700 1600);
PAINT GREEN (-1700 1600);
DISPLAY INVISIBLE (-1700 1600);
FORCEADD TAP..6
R 2
(-1700 1500);
FORCEPROP 3 LASTPIN (-1750 1500) SIG_NAME M_C_DQ<1>
J 0
(-1740 1510);
DISPLAY 0.659574 (-1740 1510);
PAINT MONO (-1740 1510);
DISPLAY INVISIBLE (-1740 1510);
FORCEPROP 1 LASTPIN (-1750 1500) BN 1
J 2
(-1700 1510);
DISPLAY 0.617021 (-1700 1510);
PAINT PINK (-1700 1510);
FORCEPROP 2 LAST CDS_LIB mstr_standard
J 2
(-1700 1500);
DISPLAY 0.787234 (-1700 1500);
PAINT MONO (-1700 1500);
DISPLAY INVISIBLE (-1700 1500);
FORCEPROP 1 LAST BODY_TYPE PLUMBING
J 2
(-1700 1450);
DISPLAY 1.234043 (-1700 1450);
PAINT GREEN (-1700 1450);
DISPLAY INVISIBLE (-1700 1450);
FORCEPROP 1 LAST HDL_TAP TRUE
J 2
(-2025 1375);
DISPLAY 1.234043 (-2025 1375);
PAINT GREEN (-2025 1375);
DISPLAY INVISIBLE (-2025 1375);
FORCEPROP 1 LAST PATH I110
J 2
(-1700 1500);
DISPLAY 0.936170 (-1700 1500);
PAINT GREEN (-1700 1500);
DISPLAY INVISIBLE (-1700 1500);
FORCEADD SCONN288_H44441004..1
(-2450 3000);
FORCEPROP 1 LAST LOCATION J4G3
J 0
(-2900 4900);
DISPLAY 0.617021 (-2900 4900);
PAINT AQUA (-2900 4900);
FORCEPROP 1 LAST PART_NUMBER H44441-004
J 0
(-2900 1000);
DISPLAY 0.617021 (-2900 1000);
PAINT BLUE (-2900 1000);
FORCEPROP 1 LAST MATERIAL SCONN
J 0
(-2900 4850);
DISPLAY 0.617021 (-2900 4850);
PAINT SKYBLUE (-2900 4850);
FORCEPROP 2 LASTPIN (-2950 1500) $PN 146
J 2
(-2960 1510);
DISPLAY 0.617021 (-2960 1510);
PAINT ORANGE (-2960 1510);
FORCEPROP 2 LASTPIN (-2950 1850) $PN 284
J 2
(-2960 1860);
DISPLAY 0.617021 (-2960 1860);
PAINT ORANGE (-2960 1860);
FORCEPROP 2 LASTPIN (-2950 1650) $PN 285
J 2
(-2960 1660);
DISPLAY 0.617021 (-2960 1660);
PAINT ORANGE (-2960 1660);
FORCEPROP 2 LASTPIN (-2950 1600) $PN 141
J 2
(-2960 1610);
DISPLAY 0.617021 (-2960 1610);
PAINT ORANGE (-2960 1610);
FORCEPROP 2 LASTPIN (-2950 1200) $PN 230
J 2
(-2960 1210);
DISPLAY 0.617021 (-2960 1210);
PAINT ORANGE (-2960 1210);
FORCEPROP 2 LASTPIN (-2950 1800) $PN 238
J 2
(-2960 1810);
DISPLAY 0.617021 (-2960 1810);
PAINT ORANGE (-2960 1810);
FORCEPROP 2 LASTPIN (-2950 1750) $PN 140
J 2
(-2960 1760);
DISPLAY 0.617021 (-2960 1760);
PAINT ORANGE (-2960 1760);
FORCEPROP 2 LASTPIN (-2950 1700) $PN 139
J 2
(-2960 1710);
DISPLAY 0.617021 (-2960 1710);
PAINT ORANGE (-2960 1710);
FORCEPROP 2 LASTPIN (-2950 3150) $PN 237
J 2
(-2960 3160);
DISPLAY 0.617021 (-2960 3160);
PAINT ORANGE (-2960 3160);
FORCEPROP 2 LASTPIN (-2950 3100) $PN 93
J 2
(-2960 3110);
DISPLAY 0.617021 (-2960 3110);
PAINT ORANGE (-2960 3110);
FORCEPROP 2 LASTPIN (-2950 3050) $PN 89
J 2
(-2960 3060);
DISPLAY 0.617021 (-2960 3060);
PAINT ORANGE (-2960 3060);
FORCEPROP 2 LASTPIN (-2950 3000) $PN 84
J 2
(-2960 3010);
DISPLAY 0.617021 (-2960 3010);
PAINT ORANGE (-2960 3010);
FORCEPROP 2 LASTPIN (-2950 1400) $PN 144
J 2
(-2960 1410);
DISPLAY 0.617021 (-2960 1410);
PAINT ORANGE (-2960 1410);
FORCEPROP 2 LASTPIN (-2950 1350) $PN 227
J 2
(-2960 1360);
DISPLAY 0.617021 (-2960 1360);
PAINT ORANGE (-2960 1360);
FORCEPROP 2 LASTPIN (-2950 1300) $PN 205
J 2
(-2960 1310);
DISPLAY 0.617021 (-2960 1310);
PAINT ORANGE (-2960 1310);
FORCEPROP 2 LASTPIN (-2950 2100) $PN 58
J 2
(-2960 2110);
DISPLAY 0.617021 (-2960 2110);
PAINT ORANGE (-2960 2110);
FORCEPROP 2 LASTPIN (-2950 2150) $PN 222
J 2
(-2960 2160);
DISPLAY 0.617021 (-2960 2160);
PAINT ORANGE (-2960 2160);
FORCEPROP 2 LASTPIN (-2950 2750) $PN 91
J 2
(-2960 2760);
DISPLAY 0.617021 (-2960 2760);
PAINT ORANGE (-2960 2760);
FORCEPROP 2 LASTPIN (-2950 2700) $PN 87
J 2
(-2960 2710);
DISPLAY 0.617021 (-2960 2710);
PAINT ORANGE (-2960 2710);
FORCEPROP 2 LASTPIN (-2950 2050) $PN 78
J 2
(-2960 2060);
DISPLAY 0.617021 (-2960 2060);
PAINT ORANGE (-2960 2060);
FORCEPROP 2 LASTPIN (-1950 4650) $PN 280
J 0
(-1940 4660);
DISPLAY 0.617021 (-1940 4660);
PAINT ORANGE (-1940 4660);
FORCEPROP 2 LASTPIN (-1950 4600) $PN 135
J 0
(-1940 4610);
DISPLAY 0.617021 (-1940 4610);
PAINT ORANGE (-1940 4610);
FORCEPROP 2 LASTPIN (-1950 4550) $PN 273
J 0
(-1940 4560);
DISPLAY 0.617021 (-1940 4560);
PAINT ORANGE (-1940 4560);
FORCEPROP 2 LASTPIN (-1950 4500) $PN 128
J 0
(-1940 4510);
DISPLAY 0.617021 (-1940 4510);
PAINT ORANGE (-1940 4510);
FORCEPROP 2 LASTPIN (-1950 4450) $PN 282
J 0
(-1940 4460);
DISPLAY 0.617021 (-1940 4460);
PAINT ORANGE (-1940 4460);
FORCEPROP 2 LASTPIN (-1950 4400) $PN 137
J 0
(-1940 4410);
DISPLAY 0.617021 (-1940 4410);
PAINT ORANGE (-1940 4410);
FORCEPROP 2 LASTPIN (-1950 4350) $PN 275
J 0
(-1940 4360);
DISPLAY 0.617021 (-1940 4360);
PAINT ORANGE (-1940 4360);
FORCEPROP 2 LASTPIN (-1950 4300) $PN 130
J 0
(-1940 4310);
DISPLAY 0.617021 (-1940 4310);
PAINT ORANGE (-1940 4310);
FORCEPROP 2 LASTPIN (-1950 4250) $PN 269
J 0
(-1940 4260);
DISPLAY 0.617021 (-1940 4260);
PAINT ORANGE (-1940 4260);
FORCEPROP 2 LASTPIN (-1950 4200) $PN 124
J 0
(-1940 4210);
DISPLAY 0.617021 (-1940 4210);
PAINT ORANGE (-1940 4210);
FORCEPROP 2 LASTPIN (-1950 4150) $PN 262
J 0
(-1940 4160);
DISPLAY 0.617021 (-1940 4160);
PAINT ORANGE (-1940 4160);
FORCEPROP 2 LASTPIN (-1950 4100) $PN 117
J 0
(-1940 4110);
DISPLAY 0.617021 (-1940 4110);
PAINT ORANGE (-1940 4110);
FORCEPROP 2 LASTPIN (-1950 4050) $PN 271
J 0
(-1940 4060);
DISPLAY 0.617021 (-1940 4060);
PAINT ORANGE (-1940 4060);
FORCEPROP 2 LASTPIN (-1950 4000) $PN 126
J 0
(-1940 4010);
DISPLAY 0.617021 (-1940 4010);
PAINT ORANGE (-1940 4010);
FORCEPROP 2 LASTPIN (-1950 3950) $PN 264
J 0
(-1940 3960);
DISPLAY 0.617021 (-1940 3960);
PAINT ORANGE (-1940 3960);
FORCEPROP 2 LASTPIN (-1950 3900) $PN 119
J 0
(-1940 3910);
DISPLAY 0.617021 (-1940 3910);
PAINT ORANGE (-1940 3910);
FORCEPROP 2 LASTPIN (-1950 3850) $PN 258
J 0
(-1940 3860);
DISPLAY 0.617021 (-1940 3860);
PAINT ORANGE (-1940 3860);
FORCEPROP 2 LASTPIN (-1950 3800) $PN 113
J 0
(-1940 3810);
DISPLAY 0.617021 (-1940 3810);
PAINT ORANGE (-1940 3810);
FORCEPROP 2 LASTPIN (-1950 3750) $PN 251
J 0
(-1940 3760);
DISPLAY 0.617021 (-1940 3760);
PAINT ORANGE (-1940 3760);
FORCEPROP 2 LASTPIN (-1950 3700) $PN 106
J 0
(-1940 3710);
DISPLAY 0.617021 (-1940 3710);
PAINT ORANGE (-1940 3710);
FORCEPROP 2 LASTPIN (-1950 3650) $PN 260
J 0
(-1940 3660);
DISPLAY 0.617021 (-1940 3660);
PAINT ORANGE (-1940 3660);
FORCEPROP 2 LASTPIN (-1950 3600) $PN 115
J 0
(-1940 3610);
DISPLAY 0.617021 (-1940 3610);
PAINT ORANGE (-1940 3610);
FORCEPROP 2 LASTPIN (-1950 3550) $PN 253
J 0
(-1940 3560);
DISPLAY 0.617021 (-1940 3560);
PAINT ORANGE (-1940 3560);
FORCEPROP 2 LASTPIN (-1950 3500) $PN 108
J 0
(-1940 3510);
DISPLAY 0.617021 (-1940 3510);
PAINT ORANGE (-1940 3510);
FORCEPROP 2 LASTPIN (-1950 3450) $PN 247
J 0
(-1940 3460);
DISPLAY 0.617021 (-1940 3460);
PAINT ORANGE (-1940 3460);
FORCEPROP 2 LASTPIN (-1950 3400) $PN 102
J 0
(-1940 3410);
DISPLAY 0.617021 (-1940 3410);
PAINT ORANGE (-1940 3410);
FORCEPROP 2 LASTPIN (-1950 3350) $PN 240
J 0
(-1940 3360);
DISPLAY 0.617021 (-1940 3360);
PAINT ORANGE (-1940 3360);
FORCEPROP 2 LASTPIN (-1950 3300) $PN 95
J 0
(-1940 3310);
DISPLAY 0.617021 (-1940 3310);
PAINT ORANGE (-1940 3310);
FORCEPROP 2 LASTPIN (-1950 3250) $PN 249
J 0
(-1940 3260);
DISPLAY 0.617021 (-1940 3260);
PAINT ORANGE (-1940 3260);
FORCEPROP 2 LASTPIN (-1950 3200) $PN 104
J 0
(-1940 3210);
DISPLAY 0.617021 (-1940 3210);
PAINT ORANGE (-1940 3210);
FORCEPROP 2 LASTPIN (-1950 3150) $PN 242
J 0
(-1940 3160);
DISPLAY 0.617021 (-1940 3160);
PAINT ORANGE (-1940 3160);
FORCEPROP 2 LASTPIN (-1950 3100) $PN 97
J 0
(-1940 3110);
DISPLAY 0.617021 (-1940 3110);
PAINT ORANGE (-1940 3110);
FORCEPROP 2 LASTPIN (-1950 3050) $PN 188
J 0
(-1940 3060);
DISPLAY 0.617021 (-1940 3060);
PAINT ORANGE (-1940 3060);
FORCEPROP 2 LASTPIN (-1950 3000) $PN 43
J 0
(-1940 3010);
DISPLAY 0.617021 (-1940 3010);
PAINT ORANGE (-1940 3010);
FORCEPROP 2 LASTPIN (-1950 2950) $PN 181
J 0
(-1940 2960);
DISPLAY 0.617021 (-1940 2960);
PAINT ORANGE (-1940 2960);
FORCEPROP 2 LASTPIN (-1950 2900) $PN 36
J 0
(-1940 2910);
DISPLAY 0.617021 (-1940 2910);
PAINT ORANGE (-1940 2910);
FORCEPROP 2 LASTPIN (-1950 2850) $PN 190
J 0
(-1940 2860);
DISPLAY 0.617021 (-1940 2860);
PAINT ORANGE (-1940 2860);
FORCEPROP 2 LASTPIN (-1950 2800) $PN 45
J 0
(-1940 2810);
DISPLAY 0.617021 (-1940 2810);
PAINT ORANGE (-1940 2810);
FORCEPROP 2 LASTPIN (-1950 2750) $PN 183
J 0
(-1940 2760);
DISPLAY 0.617021 (-1940 2760);
PAINT ORANGE (-1940 2760);
FORCEPROP 2 LASTPIN (-1950 2700) $PN 38
J 0
(-1940 2710);
DISPLAY 0.617021 (-1940 2710);
PAINT ORANGE (-1940 2710);
FORCEPROP 2 LASTPIN (-1950 2650) $PN 177
J 0
(-1940 2660);
DISPLAY 0.617021 (-1940 2660);
PAINT ORANGE (-1940 2660);
FORCEPROP 2 LASTPIN (-1950 2600) $PN 32
J 0
(-1940 2610);
DISPLAY 0.617021 (-1940 2610);
PAINT ORANGE (-1940 2610);
FORCEPROP 2 LASTPIN (-1950 2550) $PN 170
J 0
(-1940 2560);
DISPLAY 0.617021 (-1940 2560);
PAINT ORANGE (-1940 2560);
FORCEPROP 2 LASTPIN (-1950 2500) $PN 25
J 0
(-1940 2510);
DISPLAY 0.617021 (-1940 2510);
PAINT ORANGE (-1940 2510);
FORCEPROP 2 LASTPIN (-1950 2450) $PN 179
J 0
(-1940 2460);
DISPLAY 0.617021 (-1940 2460);
PAINT ORANGE (-1940 2460);
FORCEPROP 2 LASTPIN (-1950 2400) $PN 34
J 0
(-1940 2410);
DISPLAY 0.617021 (-1940 2410);
PAINT ORANGE (-1940 2410);
FORCEPROP 2 LASTPIN (-1950 2350) $PN 172
J 0
(-1940 2360);
DISPLAY 0.617021 (-1940 2360);
PAINT ORANGE (-1940 2360);
FORCEPROP 2 LASTPIN (-1950 2300) $PN 27
J 0
(-1940 2310);
DISPLAY 0.617021 (-1940 2310);
PAINT ORANGE (-1940 2310);
FORCEPROP 2 LASTPIN (-1950 2250) $PN 166
J 0
(-1940 2260);
DISPLAY 0.617021 (-1940 2260);
PAINT ORANGE (-1940 2260);
FORCEPROP 2 LASTPIN (-1950 2200) $PN 21
J 0
(-1940 2210);
DISPLAY 0.617021 (-1940 2210);
PAINT ORANGE (-1940 2210);
FORCEPROP 2 LASTPIN (-1950 2150) $PN 159
J 0
(-1940 2160);
DISPLAY 0.617021 (-1940 2160);
PAINT ORANGE (-1940 2160);
FORCEPROP 2 LASTPIN (-1950 2100) $PN 14
J 0
(-1940 2110);
DISPLAY 0.617021 (-1940 2110);
PAINT ORANGE (-1940 2110);
FORCEPROP 2 LASTPIN (-1950 2050) $PN 168
J 0
(-1940 2060);
DISPLAY 0.617021 (-1940 2060);
PAINT ORANGE (-1940 2060);
FORCEPROP 2 LASTPIN (-1950 2000) $PN 23
J 0
(-1940 2010);
DISPLAY 0.617021 (-1940 2010);
PAINT ORANGE (-1940 2010);
FORCEPROP 2 LASTPIN (-1950 1950) $PN 161
J 0
(-1940 1960);
DISPLAY 0.617021 (-1940 1960);
PAINT ORANGE (-1940 1960);
FORCEPROP 2 LASTPIN (-1950 1900) $PN 16
J 0
(-1940 1910);
DISPLAY 0.617021 (-1940 1910);
PAINT ORANGE (-1940 1910);
FORCEPROP 2 LASTPIN (-1950 1850) $PN 155
J 0
(-1940 1860);
DISPLAY 0.617021 (-1940 1860);
PAINT ORANGE (-1940 1860);
FORCEPROP 2 LASTPIN (-1950 1800) $PN 10
J 0
(-1940 1810);
DISPLAY 0.617021 (-1940 1810);
PAINT ORANGE (-1940 1810);
FORCEPROP 2 LASTPIN (-1950 1750) $PN 148
J 0
(-1940 1760);
DISPLAY 0.617021 (-1940 1760);
PAINT ORANGE (-1940 1760);
FORCEPROP 2 LASTPIN (-1950 1700) $PN 3
J 0
(-1940 1710);
DISPLAY 0.617021 (-1940 1710);
PAINT ORANGE (-1940 1710);
FORCEPROP 2 LASTPIN (-1950 1650) $PN 157
J 0
(-1940 1660);
DISPLAY 0.617021 (-1940 1660);
PAINT ORANGE (-1940 1660);
FORCEPROP 2 LASTPIN (-1950 1600) $PN 12
J 0
(-1940 1610);
DISPLAY 0.617021 (-1940 1610);
PAINT ORANGE (-1940 1610);
FORCEPROP 2 LASTPIN (-1950 1550) $PN 150
J 0
(-1940 1560);
DISPLAY 0.617021 (-1940 1560);
PAINT ORANGE (-1940 1560);
FORCEPROP 2 LASTPIN (-1950 1500) $PN 5
J 0
(-1940 1510);
DISPLAY 0.617021 (-1940 1510);
PAINT ORANGE (-1940 1510);
FORCEPROP 2 LASTPIN (-2950 2900) $PN 203
J 2
(-2960 2910);
DISPLAY 0.617021 (-2960 2910);
PAINT ORANGE (-2960 2910);
FORCEPROP 2 LASTPIN (-2950 2850) $PN 60
J 2
(-2960 2860);
DISPLAY 0.617021 (-2960 2860);
PAINT ORANGE (-2960 2860);
FORCEPROP 2 LASTPIN (-2950 3450) $PN 218
J 2
(-2960 3460);
DISPLAY 0.617021 (-2960 3460);
PAINT ORANGE (-2960 3460);
FORCEPROP 2 LASTPIN (-2950 3400) $PN 219
J 2
(-2960 3410);
DISPLAY 0.617021 (-2960 3410);
PAINT ORANGE (-2960 3410);
FORCEPROP 2 LASTPIN (-2950 3350) $PN 74
J 2
(-2960 3360);
DISPLAY 0.617021 (-2960 3360);
PAINT ORANGE (-2960 3360);
FORCEPROP 2 LASTPIN (-2950 3300) $PN 75
J 2
(-2960 3310);
DISPLAY 0.617021 (-2960 3310);
PAINT ORANGE (-2960 3310);
FORCEPROP 2 LASTPIN (-2950 2600) $PN 199
J 2
(-2960 2610);
DISPLAY 0.617021 (-2960 2610);
PAINT ORANGE (-2960 2610);
FORCEPROP 2 LASTPIN (-2950 2550) $PN 54
J 2
(-2960 2560);
DISPLAY 0.617021 (-2960 2560);
PAINT ORANGE (-2960 2560);
FORCEPROP 2 LASTPIN (-2950 2500) $PN 192
J 2
(-2960 2510);
DISPLAY 0.617021 (-2960 2510);
PAINT ORANGE (-2960 2510);
FORCEPROP 2 LASTPIN (-2950 2450) $PN 47
J 2
(-2960 2460);
DISPLAY 0.617021 (-2960 2460);
PAINT ORANGE (-2960 2460);
FORCEPROP 2 LASTPIN (-2950 2400) $PN 201
J 2
(-2960 2410);
DISPLAY 0.617021 (-2960 2410);
PAINT ORANGE (-2960 2410);
FORCEPROP 2 LASTPIN (-2950 2350) $PN 56
J 2
(-2960 2360);
DISPLAY 0.617021 (-2960 2360);
PAINT ORANGE (-2960 2360);
FORCEPROP 2 LASTPIN (-2950 2300) $PN 194
J 2
(-2960 2310);
DISPLAY 0.617021 (-2960 2310);
PAINT ORANGE (-2960 2310);
FORCEPROP 2 LASTPIN (-2950 2250) $PN 49
J 2
(-2960 2260);
DISPLAY 0.617021 (-2960 2260);
PAINT ORANGE (-2960 2260);
FORCEPROP 2 LASTPIN (-2950 3200) $PN 235
J 2
(-2960 3210);
DISPLAY 0.617021 (-2960 3210);
PAINT ORANGE (-2960 3210);
FORCEPROP 2 LASTPIN (-2950 3600) $PN 207
J 2
(-2960 3610);
DISPLAY 0.617021 (-2960 3610);
PAINT ORANGE (-2960 3610);
FORCEPROP 2 LASTPIN (-2950 3550) $PN 63
J 2
(-2960 3560);
DISPLAY 0.617021 (-2960 3560);
PAINT ORANGE (-2960 3560);
FORCEPROP 2 LASTPIN (-2950 3700) $PN 224
J 2
(-2960 3710);
DISPLAY 0.617021 (-2960 3710);
PAINT ORANGE (-2960 3710);
FORCEPROP 2 LASTPIN (-2950 3650) $PN 81
J 2
(-2960 3660);
DISPLAY 0.617021 (-2960 3660);
PAINT ORANGE (-2960 3660);
FORCEPROP 2 LASTPIN (-2950 2000) $PN 208
J 2
(-2960 2010);
DISPLAY 0.617021 (-2960 2010);
PAINT ORANGE (-2960 2010);
FORCEPROP 2 LASTPIN (-2950 1950) $PN 62
J 2
(-2960 1960);
DISPLAY 0.617021 (-2960 1960);
PAINT ORANGE (-2960 1960);
FORCEPROP 2 LASTPIN (-2950 4650) $PN 234
J 2
(-2960 4660);
DISPLAY 0.617021 (-2960 4660);
PAINT ORANGE (-2960 4660);
FORCEPROP 2 LASTPIN (-2950 4600) $PN 82
J 2
(-2960 4610);
DISPLAY 0.617021 (-2960 4610);
PAINT ORANGE (-2960 4610);
FORCEPROP 2 LASTPIN (-2950 4550) $PN 86
J 2
(-2960 4560);
DISPLAY 0.617021 (-2960 4560);
PAINT ORANGE (-2960 4560);
FORCEPROP 2 LASTPIN (-2950 4500) $PN 228
J 2
(-2960 4510);
DISPLAY 0.617021 (-2960 4510);
PAINT ORANGE (-2960 4510);
FORCEPROP 2 LASTPIN (-2950 4450) $PN 232
J 2
(-2960 4460);
DISPLAY 0.617021 (-2960 4460);
PAINT ORANGE (-2960 4460);
FORCEPROP 2 LASTPIN (-2950 4400) $PN 65
J 2
(-2960 4410);
DISPLAY 0.617021 (-2960 4410);
PAINT ORANGE (-2960 4410);
FORCEPROP 2 LASTPIN (-2950 4350) $PN 210
J 2
(-2960 4360);
DISPLAY 0.617021 (-2960 4360);
PAINT ORANGE (-2960 4360);
FORCEPROP 2 LASTPIN (-2950 4300) $PN 225
J 2
(-2960 4310);
DISPLAY 0.617021 (-2960 4310);
PAINT ORANGE (-2960 4310);
FORCEPROP 2 LASTPIN (-2950 4250) $PN 66
J 2
(-2960 4260);
DISPLAY 0.617021 (-2960 4260);
PAINT ORANGE (-2960 4260);
FORCEPROP 2 LASTPIN (-2950 4200) $PN 68
J 2
(-2960 4210);
DISPLAY 0.617021 (-2960 4210);
PAINT ORANGE (-2960 4210);
FORCEPROP 2 LASTPIN (-2950 4150) $PN 211
J 2
(-2960 4160);
DISPLAY 0.617021 (-2960 4160);
PAINT ORANGE (-2960 4160);
FORCEPROP 2 LASTPIN (-2950 4100) $PN 69
J 2
(-2960 4110);
DISPLAY 0.617021 (-2960 4110);
PAINT ORANGE (-2960 4110);
FORCEPROP 2 LASTPIN (-2950 4050) $PN 213
J 2
(-2960 4060);
DISPLAY 0.617021 (-2960 4060);
PAINT ORANGE (-2960 4060);
FORCEPROP 2 LASTPIN (-2950 4000) $PN 214
J 2
(-2960 4010);
DISPLAY 0.617021 (-2960 4010);
PAINT ORANGE (-2960 4010);
FORCEPROP 2 LASTPIN (-2950 3950) $PN 71
J 2
(-2960 3960);
DISPLAY 0.617021 (-2960 3960);
PAINT ORANGE (-2960 3960);
FORCEPROP 2 LASTPIN (-2950 3900) $PN 216
J 2
(-2960 3910);
DISPLAY 0.617021 (-2960 3910);
PAINT ORANGE (-2960 3910);
FORCEPROP 2 LASTPIN (-2950 3850) $PN 72
J 2
(-2960 3860);
DISPLAY 0.617021 (-2960 3860);
PAINT ORANGE (-2960 3860);
FORCEPROP 2 LASTPIN (-2950 3800) $PN 79
J 2
(-2960 3810);
DISPLAY 0.617021 (-2960 3810);
PAINT ORANGE (-2960 3810);
FORCEPROP 1 LAST PACK_TYPE PIP
J 0
(-2900 4950);
PAINT SKYBLUE (-2900 4950);
DISPLAY INVISIBLE (-2900 4950);
FORCEPROP 2 LAST BOM_COST MEM
J 0
(-2450 3000);
PAINT ORANGE (-2450 3000);
DISPLAY INVISIBLE (-2450 3000);
FORCEPROP 2 LAST CDS_LIB mstr_sconn
J 0
(-2450 3000);
PAINT ORANGE (-2450 3000);
DISPLAY INVISIBLE (-2450 3000);
FORCEPROP 2 LAST SEC_TYPE PIP
J 0
(-2900 4950);
DISPLAY 1.021277 (-2900 4950);
PAINT ORANGE (-2900 4950);
DISPLAY INVISIBLE (-2900 4950);
FORCEPROP 2 LAST SEC 1
J 0
(-2900 4950);
DISPLAY 0.680851 (-2900 4950);
PAINT MONO (-2900 4950);
DISPLAY INVISIBLE (-2900 4950);
FORCEPROP 2 LAST CDS_LOCATION J4G3
J 0
(-2900 4900);
DISPLAY 0.617021 (-2900 4900);
PAINT AQUA (-2900 4900);
DISPLAY INVISIBLE (-2900 4900);
FORCEPROP 1 LAST PATH I111
J 0
(-2450 4850);
PAINT GREEN (-2450 4850);
DISPLAY INVISIBLE (-2450 4850);
FORCEPROP 2 LAST ROOM DDR4_CH_C
J 0
(-2450 3000);
PAINT ORANGE (-2450 3000);
DISPLAY INVISIBLE (-2450 3000);
FORCEADD TAP..6
(-3200 4650);
FORCEPROP 3 LASTPIN (-3150 4650) SIG_NAME M_C_MA<17>
J 0
(-3140 4660);
DISPLAY 0.659574 (-3140 4660);
PAINT MONO (-3140 4660);
DISPLAY INVISIBLE (-3140 4660);
FORCEPROP 1 LASTPIN (-3150 4650) BN 17
J 0
(-3200 4660);
DISPLAY 0.617021 (-3200 4660);
PAINT PINK (-3200 4660);
FORCEPROP 2 LAST CDS_LIB mstr_standard
J 0
(-3200 4650);
DISPLAY 0.787234 (-3200 4650);
PAINT MONO (-3200 4650);
DISPLAY INVISIBLE (-3200 4650);
FORCEPROP 1 LAST BODY_TYPE PLUMBING
J 0
(-3200 4600);
DISPLAY 1.234043 (-3200 4600);
PAINT GREEN (-3200 4600);
DISPLAY INVISIBLE (-3200 4600);
FORCEPROP 1 LAST HDL_TAP TRUE
J 0
(-2875 4525);
DISPLAY 1.234043 (-2875 4525);
PAINT GREEN (-2875 4525);
DISPLAY INVISIBLE (-2875 4525);
FORCEPROP 1 LAST PATH I112
J 0
(-3200 4650);
DISPLAY 0.936170 (-3200 4650);
PAINT GREEN (-3200 4650);
DISPLAY INVISIBLE (-3200 4650);
FORCEADD TAP..6
(-3200 4600);
FORCEPROP 3 LASTPIN (-3150 4600) SIG_NAME M_C_MA<16>
J 0
(-3140 4610);
DISPLAY 0.659574 (-3140 4610);
PAINT MONO (-3140 4610);
DISPLAY INVISIBLE (-3140 4610);
FORCEPROP 1 LASTPIN (-3150 4600) BN 16
J 0
(-3200 4610);
DISPLAY 0.617021 (-3200 4610);
PAINT PINK (-3200 4610);
FORCEPROP 2 LAST CDS_LIB mstr_standard
J 2
(-3200 4600);
DISPLAY 0.787234 (-3200 4600);
PAINT MONO (-3200 4600);
DISPLAY INVISIBLE (-3200 4600);
FORCEPROP 1 LAST BODY_TYPE PLUMBING
J 0
(-3200 4550);
DISPLAY 1.234043 (-3200 4550);
PAINT GREEN (-3200 4550);
DISPLAY INVISIBLE (-3200 4550);
FORCEPROP 1 LAST HDL_TAP TRUE
J 0
(-2875 4475);
DISPLAY 1.234043 (-2875 4475);
PAINT GREEN (-2875 4475);
DISPLAY INVISIBLE (-2875 4475);
FORCEPROP 1 LAST PATH I113
J 0
(-3200 4600);
DISPLAY 0.936170 (-3200 4600);
PAINT GREEN (-3200 4600);
DISPLAY INVISIBLE (-3200 4600);
FORCEADD TAP..6
(-3200 4550);
FORCEPROP 3 LASTPIN (-3150 4550) SIG_NAME M_C_MA<15>
J 0
(-3140 4560);
DISPLAY 0.659574 (-3140 4560);
PAINT MONO (-3140 4560);
DISPLAY INVISIBLE (-3140 4560);
FORCEPROP 1 LASTPIN (-3150 4550) BN 15
J 0
(-3200 4560);
DISPLAY 0.617021 (-3200 4560);
PAINT PINK (-3200 4560);
FORCEPROP 2 LAST CDS_LIB mstr_standard
J 2
(-3200 4550);
DISPLAY 0.787234 (-3200 4550);
PAINT MONO (-3200 4550);
DISPLAY INVISIBLE (-3200 4550);
FORCEPROP 1 LAST BODY_TYPE PLUMBING
J 0
(-3200 4500);
DISPLAY 1.234043 (-3200 4500);
PAINT GREEN (-3200 4500);
DISPLAY INVISIBLE (-3200 4500);
FORCEPROP 1 LAST HDL_TAP TRUE
J 0
(-2875 4425);
DISPLAY 1.234043 (-2875 4425);
PAINT GREEN (-2875 4425);
DISPLAY INVISIBLE (-2875 4425);
FORCEPROP 1 LAST PATH I114
J 0
(-3200 4550);
DISPLAY 0.936170 (-3200 4550);
PAINT GREEN (-3200 4550);
DISPLAY INVISIBLE (-3200 4550);
FORCEADD TAP..6
(-3200 4500);
FORCEPROP 3 LASTPIN (-3150 4500) SIG_NAME M_C_MA<14>
J 0
(-3140 4510);
DISPLAY 0.659574 (-3140 4510);
PAINT MONO (-3140 4510);
DISPLAY INVISIBLE (-3140 4510);
FORCEPROP 1 LASTPIN (-3150 4500) BN 14
J 0
(-3200 4510);
DISPLAY 0.617021 (-3200 4510);
PAINT PINK (-3200 4510);
FORCEPROP 2 LAST CDS_LIB mstr_standard
J 2
(-3200 4500);
DISPLAY 0.787234 (-3200 4500);
PAINT MONO (-3200 4500);
DISPLAY INVISIBLE (-3200 4500);
FORCEPROP 1 LAST BODY_TYPE PLUMBING
J 0
(-3200 4450);
DISPLAY 1.234043 (-3200 4450);
PAINT GREEN (-3200 4450);
DISPLAY INVISIBLE (-3200 4450);
FORCEPROP 1 LAST HDL_TAP TRUE
J 0
(-2875 4375);
DISPLAY 1.234043 (-2875 4375);
PAINT GREEN (-2875 4375);
DISPLAY INVISIBLE (-2875 4375);
FORCEPROP 1 LAST PATH I115
J 0
(-3200 4500);
DISPLAY 0.936170 (-3200 4500);
PAINT GREEN (-3200 4500);
DISPLAY INVISIBLE (-3200 4500);
FORCEADD TAP..6
(-3200 4450);
FORCEPROP 3 LASTPIN (-3150 4450) SIG_NAME M_C_MA<13>
J 0
(-3140 4460);
DISPLAY 0.659574 (-3140 4460);
PAINT MONO (-3140 4460);
DISPLAY INVISIBLE (-3140 4460);
FORCEPROP 1 LASTPIN (-3150 4450) BN 13
J 0
(-3200 4460);
DISPLAY 0.617021 (-3200 4460);
PAINT PINK (-3200 4460);
FORCEPROP 2 LAST CDS_LIB mstr_standard
J 2
(-3200 4450);
DISPLAY 0.787234 (-3200 4450);
PAINT MONO (-3200 4450);
DISPLAY INVISIBLE (-3200 4450);
FORCEPROP 1 LAST BODY_TYPE PLUMBING
J 0
(-3200 4400);
DISPLAY 1.234043 (-3200 4400);
PAINT GREEN (-3200 4400);
DISPLAY INVISIBLE (-3200 4400);
FORCEPROP 1 LAST HDL_TAP TRUE
J 0
(-2875 4325);
DISPLAY 1.234043 (-2875 4325);
PAINT GREEN (-2875 4325);
DISPLAY INVISIBLE (-2875 4325);
FORCEPROP 1 LAST PATH I116
J 0
(-3200 4450);
DISPLAY 0.936170 (-3200 4450);
PAINT GREEN (-3200 4450);
DISPLAY INVISIBLE (-3200 4450);
FORCEADD TAP..6
(-3200 4400);
FORCEPROP 3 LASTPIN (-3150 4400) SIG_NAME M_C_MA<12>
J 0
(-3140 4410);
DISPLAY 0.659574 (-3140 4410);
PAINT MONO (-3140 4410);
DISPLAY INVISIBLE (-3140 4410);
FORCEPROP 1 LASTPIN (-3150 4400) BN 12
J 0
(-3200 4410);
DISPLAY 0.617021 (-3200 4410);
PAINT PINK (-3200 4410);
FORCEPROP 2 LAST CDS_LIB mstr_standard
J 2
(-3200 4400);
DISPLAY 0.787234 (-3200 4400);
PAINT MONO (-3200 4400);
DISPLAY INVISIBLE (-3200 4400);
FORCEPROP 1 LAST BODY_TYPE PLUMBING
J 0
(-3200 4350);
DISPLAY 1.234043 (-3200 4350);
PAINT GREEN (-3200 4350);
DISPLAY INVISIBLE (-3200 4350);
FORCEPROP 1 LAST HDL_TAP TRUE
J 0
(-2875 4275);
DISPLAY 1.234043 (-2875 4275);
PAINT GREEN (-2875 4275);
DISPLAY INVISIBLE (-2875 4275);
FORCEPROP 1 LAST PATH I117
J 0
(-3200 4400);
DISPLAY 0.936170 (-3200 4400);
PAINT GREEN (-3200 4400);
DISPLAY INVISIBLE (-3200 4400);
FORCEADD TAP..6
(-3200 4350);
FORCEPROP 3 LASTPIN (-3150 4350) SIG_NAME M_C_MA<11>
J 0
(-3140 4360);
DISPLAY 0.659574 (-3140 4360);
PAINT MONO (-3140 4360);
DISPLAY INVISIBLE (-3140 4360);
FORCEPROP 1 LASTPIN (-3150 4350) BN 11
J 0
(-3200 4360);
DISPLAY 0.617021 (-3200 4360);
PAINT PINK (-3200 4360);
FORCEPROP 2 LAST CDS_LIB mstr_standard
J 2
(-3200 4350);
DISPLAY 0.787234 (-3200 4350);
PAINT MONO (-3200 4350);
DISPLAY INVISIBLE (-3200 4350);
FORCEPROP 1 LAST BODY_TYPE PLUMBING
J 0
(-3200 4300);
DISPLAY 1.234043 (-3200 4300);
PAINT GREEN (-3200 4300);
DISPLAY INVISIBLE (-3200 4300);
FORCEPROP 1 LAST HDL_TAP TRUE
J 0
(-2875 4225);
DISPLAY 1.234043 (-2875 4225);
PAINT GREEN (-2875 4225);
DISPLAY INVISIBLE (-2875 4225);
FORCEPROP 1 LAST PATH I118
J 0
(-3200 4350);
DISPLAY 0.936170 (-3200 4350);
PAINT GREEN (-3200 4350);
DISPLAY INVISIBLE (-3200 4350);
FORCEADD TAP..6
(-3200 4300);
FORCEPROP 3 LASTPIN (-3150 4300) SIG_NAME M_C_MA<10>
J 0
(-3140 4310);
DISPLAY 0.659574 (-3140 4310);
PAINT MONO (-3140 4310);
DISPLAY INVISIBLE (-3140 4310);
FORCEPROP 1 LASTPIN (-3150 4300) BN 10
J 0
(-3200 4310);
DISPLAY 0.617021 (-3200 4310);
PAINT PINK (-3200 4310);
FORCEPROP 2 LAST CDS_LIB mstr_standard
J 2
(-3200 4300);
DISPLAY 0.787234 (-3200 4300);
PAINT MONO (-3200 4300);
DISPLAY INVISIBLE (-3200 4300);
FORCEPROP 1 LAST BODY_TYPE PLUMBING
J 0
(-3200 4250);
DISPLAY 1.234043 (-3200 4250);
PAINT GREEN (-3200 4250);
DISPLAY INVISIBLE (-3200 4250);
FORCEPROP 1 LAST HDL_TAP TRUE
J 0
(-2875 4175);
DISPLAY 1.234043 (-2875 4175);
PAINT GREEN (-2875 4175);
DISPLAY INVISIBLE (-2875 4175);
FORCEPROP 1 LAST PATH I119
J 0
(-3200 4300);
DISPLAY 0.936170 (-3200 4300);
PAINT GREEN (-3200 4300);
DISPLAY INVISIBLE (-3200 4300);
FORCEADD PVTT_ABC..1
(-850 2700);
FORCEPROP 3 LASTPIN (-850 2650) SIG_NAME PVTT_ABC\g
J 0
(-840 2660);
DISPLAY 0.659574 (-840 2660);
PAINT MONO (-840 2660);
DISPLAY INVISIBLE (-840 2660);
FORCEPROP 1 LAST VOLTAGE 0.6V
J 0
(-895 2657);
DISPLAY 0.340426 (-895 2657);
PAINT SKYBLUE (-895 2657);
DISPLAY INVISIBLE (-895 2657);
FORCEPROP 2 LAST BOM_COST MEM
J 0
(-850 2705);
PAINT ORANGE (-850 2705);
DISPLAY INVISIBLE (-850 2705);
FORCEPROP 2 LAST CDS_LIB mstr_symbols
J 0
(-850 2700);
PAINT ORANGE (-850 2700);
DISPLAY INVISIBLE (-850 2700);
FORCEPROP 1 LAST BODY_TYPE PLUMBING
J 0
(-895 2657);
DISPLAY 0.340426 (-895 2657);
PAINT GREEN (-895 2657);
DISPLAY INVISIBLE (-895 2657);
FORCEPROP 1 LAST PATH I12
J 0
(-800 2725);
DISPLAY 0.872340 (-800 2725);
PAINT AQUA (-800 2725);
DISPLAY INVISIBLE (-800 2725);
FORCEPROP 2 LAST ROOM DDR4_CH_A
J 0
(-850 2800);
DISPLAY 0.787234 (-850 2800);
PAINT ORANGE (-850 2800);
DISPLAY INVISIBLE (-850 2800);
FORCEPROP 1 LAST HDL_POWER PVTT_ABC
J 1
(-850 2750);
DISPLAY 0.872340 (-850 2750);
PAINT GREEN (-850 2750);
DISPLAY INVISIBLE (-850 2750);
FORCEADD TAP..6
(-3200 4250);
FORCEPROP 3 LASTPIN (-3150 4250) SIG_NAME M_C_MA<9>
J 0
(-3140 4260);
DISPLAY 0.659574 (-3140 4260);
PAINT MONO (-3140 4260);
DISPLAY INVISIBLE (-3140 4260);
FORCEPROP 1 LASTPIN (-3150 4250) BN 9
J 0
(-3200 4260);
DISPLAY 0.617021 (-3200 4260);
PAINT PINK (-3200 4260);
FORCEPROP 2 LAST CDS_LIB mstr_standard
J 2
(-3200 4250);
DISPLAY 0.787234 (-3200 4250);
PAINT MONO (-3200 4250);
DISPLAY INVISIBLE (-3200 4250);
FORCEPROP 1 LAST BODY_TYPE PLUMBING
J 0
(-3200 4200);
DISPLAY 1.234043 (-3200 4200);
PAINT GREEN (-3200 4200);
DISPLAY INVISIBLE (-3200 4200);
FORCEPROP 1 LAST HDL_TAP TRUE
J 0
(-2875 4125);
DISPLAY 1.234043 (-2875 4125);
PAINT GREEN (-2875 4125);
DISPLAY INVISIBLE (-2875 4125);
FORCEPROP 1 LAST PATH I120
J 0
(-3200 4250);
DISPLAY 0.936170 (-3200 4250);
PAINT GREEN (-3200 4250);
DISPLAY INVISIBLE (-3200 4250);
FORCEADD TAP..6
(-3200 4200);
FORCEPROP 3 LASTPIN (-3150 4200) SIG_NAME M_C_MA<8>
J 0
(-3140 4210);
DISPLAY 0.659574 (-3140 4210);
PAINT MONO (-3140 4210);
DISPLAY INVISIBLE (-3140 4210);
FORCEPROP 1 LASTPIN (-3150 4200) BN 8
J 0
(-3200 4210);
DISPLAY 0.617021 (-3200 4210);
PAINT PINK (-3200 4210);
FORCEPROP 2 LAST CDS_LIB mstr_standard
J 2
(-3200 4200);
DISPLAY 0.787234 (-3200 4200);
PAINT MONO (-3200 4200);
DISPLAY INVISIBLE (-3200 4200);
FORCEPROP 1 LAST BODY_TYPE PLUMBING
J 0
(-3200 4150);
DISPLAY 1.234043 (-3200 4150);
PAINT GREEN (-3200 4150);
DISPLAY INVISIBLE (-3200 4150);
FORCEPROP 1 LAST HDL_TAP TRUE
J 0
(-2875 4075);
DISPLAY 1.234043 (-2875 4075);
PAINT GREEN (-2875 4075);
DISPLAY INVISIBLE (-2875 4075);
FORCEPROP 1 LAST PATH I121
J 0
(-3200 4200);
DISPLAY 0.936170 (-3200 4200);
PAINT GREEN (-3200 4200);
DISPLAY INVISIBLE (-3200 4200);
FORCEADD TAP..6
(-3200 4150);
FORCEPROP 3 LASTPIN (-3150 4150) SIG_NAME M_C_MA<7>
J 0
(-3140 4160);
DISPLAY 0.659574 (-3140 4160);
PAINT MONO (-3140 4160);
DISPLAY INVISIBLE (-3140 4160);
FORCEPROP 1 LASTPIN (-3150 4150) BN 7
J 0
(-3200 4160);
DISPLAY 0.617021 (-3200 4160);
PAINT PINK (-3200 4160);
FORCEPROP 2 LAST CDS_LIB mstr_standard
J 2
(-3200 4150);
DISPLAY 0.787234 (-3200 4150);
PAINT MONO (-3200 4150);
DISPLAY INVISIBLE (-3200 4150);
FORCEPROP 1 LAST BODY_TYPE PLUMBING
J 0
(-3200 4100);
DISPLAY 1.234043 (-3200 4100);
PAINT GREEN (-3200 4100);
DISPLAY INVISIBLE (-3200 4100);
FORCEPROP 1 LAST HDL_TAP TRUE
J 0
(-2875 4025);
DISPLAY 1.234043 (-2875 4025);
PAINT GREEN (-2875 4025);
DISPLAY INVISIBLE (-2875 4025);
FORCEPROP 1 LAST PATH I122
J 0
(-3200 4150);
DISPLAY 0.936170 (-3200 4150);
PAINT GREEN (-3200 4150);
DISPLAY INVISIBLE (-3200 4150);
FORCEADD TAP..6
(-3200 4100);
FORCEPROP 3 LASTPIN (-3150 4100) SIG_NAME M_C_MA<6>
J 0
(-3140 4110);
DISPLAY 0.659574 (-3140 4110);
PAINT MONO (-3140 4110);
DISPLAY INVISIBLE (-3140 4110);
FORCEPROP 1 LASTPIN (-3150 4100) BN 6
J 0
(-3200 4110);
DISPLAY 0.617021 (-3200 4110);
PAINT PINK (-3200 4110);
FORCEPROP 2 LAST CDS_LIB mstr_standard
J 2
(-3200 4100);
DISPLAY 0.787234 (-3200 4100);
PAINT MONO (-3200 4100);
DISPLAY INVISIBLE (-3200 4100);
FORCEPROP 1 LAST BODY_TYPE PLUMBING
J 0
(-3200 4050);
DISPLAY 1.234043 (-3200 4050);
PAINT GREEN (-3200 4050);
DISPLAY INVISIBLE (-3200 4050);
FORCEPROP 1 LAST HDL_TAP TRUE
J 0
(-2875 3975);
DISPLAY 1.234043 (-2875 3975);
PAINT GREEN (-2875 3975);
DISPLAY INVISIBLE (-2875 3975);
FORCEPROP 1 LAST PATH I123
J 0
(-3200 4100);
DISPLAY 0.936170 (-3200 4100);
PAINT GREEN (-3200 4100);
DISPLAY INVISIBLE (-3200 4100);
FORCEADD TAP..6
(-3200 4050);
FORCEPROP 3 LASTPIN (-3150 4050) SIG_NAME M_C_MA<5>
J 0
(-3140 4060);
DISPLAY 0.659574 (-3140 4060);
PAINT MONO (-3140 4060);
DISPLAY INVISIBLE (-3140 4060);
FORCEPROP 1 LASTPIN (-3150 4050) BN 5
J 0
(-3200 4060);
DISPLAY 0.617021 (-3200 4060);
PAINT PINK (-3200 4060);
FORCEPROP 2 LAST CDS_LIB mstr_standard
J 2
(-3200 4050);
DISPLAY 0.787234 (-3200 4050);
PAINT MONO (-3200 4050);
DISPLAY INVISIBLE (-3200 4050);
FORCEPROP 1 LAST BODY_TYPE PLUMBING
J 0
(-3200 4000);
DISPLAY 1.234043 (-3200 4000);
PAINT GREEN (-3200 4000);
DISPLAY INVISIBLE (-3200 4000);
FORCEPROP 1 LAST HDL_TAP TRUE
J 0
(-2875 3925);
DISPLAY 1.234043 (-2875 3925);
PAINT GREEN (-2875 3925);
DISPLAY INVISIBLE (-2875 3925);
FORCEPROP 1 LAST PATH I124
J 0
(-3200 4050);
DISPLAY 0.936170 (-3200 4050);
PAINT GREEN (-3200 4050);
DISPLAY INVISIBLE (-3200 4050);
FORCEADD TAP..6
(-3200 4000);
FORCEPROP 3 LASTPIN (-3150 4000) SIG_NAME M_C_MA<4>
J 0
(-3140 4010);
DISPLAY 0.659574 (-3140 4010);
PAINT MONO (-3140 4010);
DISPLAY INVISIBLE (-3140 4010);
FORCEPROP 1 LASTPIN (-3150 4000) BN 4
J 0
(-3200 4010);
DISPLAY 0.617021 (-3200 4010);
PAINT PINK (-3200 4010);
FORCEPROP 2 LAST CDS_LIB mstr_standard
J 2
(-3200 4000);
DISPLAY 0.787234 (-3200 4000);
PAINT MONO (-3200 4000);
DISPLAY INVISIBLE (-3200 4000);
FORCEPROP 1 LAST BODY_TYPE PLUMBING
J 0
(-3200 3950);
DISPLAY 1.234043 (-3200 3950);
PAINT GREEN (-3200 3950);
DISPLAY INVISIBLE (-3200 3950);
FORCEPROP 1 LAST HDL_TAP TRUE
J 0
(-2875 3875);
DISPLAY 1.234043 (-2875 3875);
PAINT GREEN (-2875 3875);
DISPLAY INVISIBLE (-2875 3875);
FORCEPROP 1 LAST PATH I125
J 0
(-3200 4000);
DISPLAY 0.936170 (-3200 4000);
PAINT GREEN (-3200 4000);
DISPLAY INVISIBLE (-3200 4000);
FORCEADD TAP..6
(-3200 3950);
FORCEPROP 3 LASTPIN (-3150 3950) SIG_NAME M_C_MA<3>
J 0
(-3140 3960);
DISPLAY 0.659574 (-3140 3960);
PAINT MONO (-3140 3960);
DISPLAY INVISIBLE (-3140 3960);
FORCEPROP 1 LASTPIN (-3150 3950) BN 3
J 0
(-3200 3960);
DISPLAY 0.617021 (-3200 3960);
PAINT PINK (-3200 3960);
FORCEPROP 2 LAST CDS_LIB mstr_standard
J 2
(-3200 3950);
DISPLAY 0.787234 (-3200 3950);
PAINT MONO (-3200 3950);
DISPLAY INVISIBLE (-3200 3950);
FORCEPROP 1 LAST BODY_TYPE PLUMBING
J 0
(-3200 3900);
DISPLAY 1.234043 (-3200 3900);
PAINT GREEN (-3200 3900);
DISPLAY INVISIBLE (-3200 3900);
FORCEPROP 1 LAST HDL_TAP TRUE
J 0
(-2875 3825);
DISPLAY 1.234043 (-2875 3825);
PAINT GREEN (-2875 3825);
DISPLAY INVISIBLE (-2875 3825);
FORCEPROP 1 LAST PATH I126
J 0
(-3200 3950);
DISPLAY 0.936170 (-3200 3950);
PAINT GREEN (-3200 3950);
DISPLAY INVISIBLE (-3200 3950);
FORCEADD OFFPAGE..1
(-3800 4700);
FORCEPROP 2 LAST $XR0 25 
J 0
(-4051 4700);
DISPLAY 0.638298 (-4051 4700);
PAINT MONO (-4051 4700);
FORCEPROP 2 LAST $XR1 48 
J 0
(-4141 4700);
DISPLAY 0.638298 (-4141 4700);
PAINT MONO (-4141 4700);
FORCEPROP 2 LAST CDS_LIB mstr_standard
J 0
(-3800 4700);
DISPLAY 0.787234 (-3800 4700);
PAINT MONO (-3800 4700);
DISPLAY INVISIBLE (-3800 4700);
FORCEPROP 1 LAST OFFPAGE TRUE
J 0
(-3475 4575);
DISPLAY 0.936170 (-3475 4575);
PAINT GREEN (-3475 4575);
DISPLAY INVISIBLE (-3475 4575);
FORCEPROP 1 LAST COMMENT_BODY TRUE
J 0
(-3675 4600);
DISPLAY 0.936170 (-3675 4600);
PAINT GREEN (-3675 4600);
DISPLAY INVISIBLE (-3675 4600);
FORCEPROP 2 LAST PATH I127
J 0
(-3750 4775);
DISPLAY 0.787234 (-3750 4775);
PAINT MONO (-3750 4775);
DISPLAY INVISIBLE (-3750 4775);
FORCEADD TAP..6
(-3200 3900);
FORCEPROP 3 LASTPIN (-3150 3900) SIG_NAME M_C_MA<2>
J 0
(-3140 3910);
DISPLAY 0.659574 (-3140 3910);
PAINT MONO (-3140 3910);
DISPLAY INVISIBLE (-3140 3910);
FORCEPROP 1 LASTPIN (-3150 3900) BN 2
J 0
(-3200 3910);
DISPLAY 0.617021 (-3200 3910);
PAINT PINK (-3200 3910);
FORCEPROP 2 LAST CDS_LIB mstr_standard
J 2
(-3200 3900);
DISPLAY 0.787234 (-3200 3900);
PAINT MONO (-3200 3900);
DISPLAY INVISIBLE (-3200 3900);
FORCEPROP 1 LAST BODY_TYPE PLUMBING
J 0
(-3200 3850);
DISPLAY 1.234043 (-3200 3850);
PAINT GREEN (-3200 3850);
DISPLAY INVISIBLE (-3200 3850);
FORCEPROP 1 LAST HDL_TAP TRUE
J 0
(-2875 3775);
DISPLAY 1.234043 (-2875 3775);
PAINT GREEN (-2875 3775);
DISPLAY INVISIBLE (-2875 3775);
FORCEPROP 1 LAST PATH I128
J 0
(-3200 3900);
DISPLAY 0.936170 (-3200 3900);
PAINT GREEN (-3200 3900);
DISPLAY INVISIBLE (-3200 3900);
FORCEADD TAP..6
(-3200 3850);
FORCEPROP 3 LASTPIN (-3150 3850) SIG_NAME M_C_MA<1>
J 0
(-3140 3860);
DISPLAY 0.659574 (-3140 3860);
PAINT MONO (-3140 3860);
DISPLAY INVISIBLE (-3140 3860);
FORCEPROP 1 LASTPIN (-3150 3850) BN 1
J 0
(-3200 3860);
DISPLAY 0.617021 (-3200 3860);
PAINT PINK (-3200 3860);
FORCEPROP 2 LAST CDS_LIB mstr_standard
J 2
(-3200 3850);
DISPLAY 0.787234 (-3200 3850);
PAINT MONO (-3200 3850);
DISPLAY INVISIBLE (-3200 3850);
FORCEPROP 1 LAST BODY_TYPE PLUMBING
J 0
(-3200 3800);
DISPLAY 1.234043 (-3200 3800);
PAINT GREEN (-3200 3800);
DISPLAY INVISIBLE (-3200 3800);
FORCEPROP 1 LAST HDL_TAP TRUE
J 0
(-2875 3725);
DISPLAY 1.234043 (-2875 3725);
PAINT GREEN (-2875 3725);
DISPLAY INVISIBLE (-2875 3725);
FORCEPROP 1 LAST PATH I129
J 0
(-3200 3850);
DISPLAY 0.936170 (-3200 3850);
PAINT GREEN (-3200 3850);
DISPLAY INVISIBLE (-3200 3850);
FORCEADD PVDDQ_ABC..1
(-1150 2600);
FORCEPROP 3 LASTPIN (-1150 2550) SIG_NAME PVDDQ_ABC\g
J 0
(-1140 2560);
DISPLAY 0.659574 (-1140 2560);
PAINT MONO (-1140 2560);
DISPLAY INVISIBLE (-1140 2560);
FORCEPROP 1 LAST VOLTAGE 1.2V
J 0
(-1195 2557);
DISPLAY 0.340426 (-1195 2557);
PAINT SKYBLUE (-1195 2557);
DISPLAY INVISIBLE (-1195 2557);
FORCEPROP 2 LAST BOM_COST MEM
J 0
(-1150 2605);
PAINT ORANGE (-1150 2605);
DISPLAY INVISIBLE (-1150 2605);
FORCEPROP 2 LAST CDS_LIB mstr_symbols
J 0
(-1150 2600);
PAINT ORANGE (-1150 2600);
DISPLAY INVISIBLE (-1150 2600);
FORCEPROP 1 LAST BODY_TYPE PLUMBING
J 0
(-1195 2557);
DISPLAY 0.340426 (-1195 2557);
PAINT GREEN (-1195 2557);
DISPLAY INVISIBLE (-1195 2557);
FORCEPROP 1 LAST PATH I13
J 0
(-1100 2625);
DISPLAY 0.872340 (-1100 2625);
PAINT AQUA (-1100 2625);
DISPLAY INVISIBLE (-1100 2625);
FORCEPROP 2 LAST ROOM DDR4_CH_A
J 0
(-1150 2700);
DISPLAY 0.787234 (-1150 2700);
PAINT ORANGE (-1150 2700);
DISPLAY INVISIBLE (-1150 2700);
FORCEPROP 1 LAST HDL_POWER PVDDQ_ABC
J 1
(-1150 2650);
DISPLAY 0.872340 (-1150 2650);
PAINT GREEN (-1150 2650);
DISPLAY INVISIBLE (-1150 2650);
FORCEADD TAP..6
(-3200 3800);
FORCEPROP 3 LASTPIN (-3150 3800) SIG_NAME M_C_MA<0>
J 0
(-3140 3810);
DISPLAY 0.659574 (-3140 3810);
PAINT MONO (-3140 3810);
DISPLAY INVISIBLE (-3140 3810);
FORCEPROP 1 LASTPIN (-3150 3800) BN 0
J 0
(-3200 3810);
DISPLAY 0.617021 (-3200 3810);
PAINT PINK (-3200 3810);
FORCEPROP 2 LAST CDS_LIB mstr_standard
J 2
(-3200 3800);
DISPLAY 0.787234 (-3200 3800);
PAINT MONO (-3200 3800);
DISPLAY INVISIBLE (-3200 3800);
FORCEPROP 1 LAST BODY_TYPE PLUMBING
J 0
(-3200 3750);
DISPLAY 1.234043 (-3200 3750);
PAINT GREEN (-3200 3750);
DISPLAY INVISIBLE (-3200 3750);
FORCEPROP 1 LAST HDL_TAP TRUE
J 0
(-2875 3675);
DISPLAY 1.234043 (-2875 3675);
PAINT GREEN (-2875 3675);
DISPLAY INVISIBLE (-2875 3675);
FORCEPROP 1 LAST PATH I130
J 0
(-3200 3800);
DISPLAY 0.936170 (-3200 3800);
PAINT GREEN (-3200 3800);
DISPLAY INVISIBLE (-3200 3800);
FORCEADD TAP..6
(-3200 3700);
FORCEPROP 3 LASTPIN (-3150 3700) SIG_NAME M_C_BA<1>
J 0
(-3140 3710);
DISPLAY 0.659574 (-3140 3710);
PAINT MONO (-3140 3710);
DISPLAY INVISIBLE (-3140 3710);
FORCEPROP 1 LASTPIN (-3150 3700) BN 1
J 0
(-3200 3710);
DISPLAY 0.617021 (-3200 3710);
PAINT PINK (-3200 3710);
FORCEPROP 2 LAST CDS_LIB mstr_standard
J 0
(-3200 3700);
DISPLAY 0.787234 (-3200 3700);
PAINT MONO (-3200 3700);
DISPLAY INVISIBLE (-3200 3700);
FORCEPROP 1 LAST BODY_TYPE PLUMBING
J 0
(-3200 3650);
DISPLAY 1.234043 (-3200 3650);
PAINT GREEN (-3200 3650);
DISPLAY INVISIBLE (-3200 3650);
FORCEPROP 1 LAST HDL_TAP TRUE
J 0
(-2875 3575);
DISPLAY 1.234043 (-2875 3575);
PAINT GREEN (-2875 3575);
DISPLAY INVISIBLE (-2875 3575);
FORCEPROP 1 LAST PATH I131
J 0
(-3200 3700);
DISPLAY 0.936170 (-3200 3700);
PAINT GREEN (-3200 3700);
DISPLAY INVISIBLE (-3200 3700);
FORCEADD TAP..6
(-3200 3650);
FORCEPROP 3 LASTPIN (-3150 3650) SIG_NAME M_C_BA<0>
J 0
(-3140 3660);
DISPLAY 0.659574 (-3140 3660);
PAINT MONO (-3140 3660);
DISPLAY INVISIBLE (-3140 3660);
FORCEPROP 1 LASTPIN (-3150 3650) BN 0
J 0
(-3200 3660);
DISPLAY 0.617021 (-3200 3660);
PAINT PINK (-3200 3660);
FORCEPROP 2 LAST CDS_LIB mstr_standard
J 0
(-3200 3650);
DISPLAY 0.787234 (-3200 3650);
PAINT MONO (-3200 3650);
DISPLAY INVISIBLE (-3200 3650);
FORCEPROP 1 LAST BODY_TYPE PLUMBING
J 0
(-3200 3600);
DISPLAY 1.234043 (-3200 3600);
PAINT GREEN (-3200 3600);
DISPLAY INVISIBLE (-3200 3600);
FORCEPROP 1 LAST HDL_TAP TRUE
J 0
(-2875 3525);
DISPLAY 1.234043 (-2875 3525);
PAINT GREEN (-2875 3525);
DISPLAY INVISIBLE (-2875 3525);
FORCEPROP 1 LAST PATH I132
J 0
(-3200 3650);
DISPLAY 0.936170 (-3200 3650);
PAINT GREEN (-3200 3650);
DISPLAY INVISIBLE (-3200 3650);
FORCEADD TAP..6
(-3200 3550);
FORCEPROP 3 LASTPIN (-3150 3550) SIG_NAME M_C_BG<0>
J 0
(-3140 3560);
DISPLAY 0.659574 (-3140 3560);
PAINT MONO (-3140 3560);
DISPLAY INVISIBLE (-3140 3560);
FORCEPROP 1 LASTPIN (-3150 3550) BN 0
J 0
(-3200 3560);
DISPLAY 0.617021 (-3200 3560);
PAINT PINK (-3200 3560);
FORCEPROP 2 LAST CDS_LIB mstr_standard
J 0
(-3200 3550);
DISPLAY 0.787234 (-3200 3550);
PAINT MONO (-3200 3550);
DISPLAY INVISIBLE (-3200 3550);
FORCEPROP 1 LAST BODY_TYPE PLUMBING
J 0
(-3200 3500);
DISPLAY 1.234043 (-3200 3500);
PAINT GREEN (-3200 3500);
DISPLAY INVISIBLE (-3200 3500);
FORCEPROP 1 LAST HDL_TAP TRUE
J 0
(-2875 3425);
DISPLAY 1.234043 (-2875 3425);
PAINT GREEN (-2875 3425);
DISPLAY INVISIBLE (-2875 3425);
FORCEPROP 1 LAST PATH I133
J 0
(-3200 3550);
DISPLAY 0.936170 (-3200 3550);
PAINT GREEN (-3200 3550);
DISPLAY INVISIBLE (-3200 3550);
FORCEADD TAP..6
(-3200 3600);
FORCEPROP 3 LASTPIN (-3150 3600) SIG_NAME M_C_BG<1>
J 0
(-3140 3610);
DISPLAY 0.659574 (-3140 3610);
PAINT MONO (-3140 3610);
DISPLAY INVISIBLE (-3140 3610);
FORCEPROP 1 LASTPIN (-3150 3600) BN 1
J 0
(-3200 3610);
DISPLAY 0.617021 (-3200 3610);
PAINT PINK (-3200 3610);
FORCEPROP 2 LAST CDS_LIB mstr_standard
J 0
(-3200 3600);
DISPLAY 0.787234 (-3200 3600);
PAINT MONO (-3200 3600);
DISPLAY INVISIBLE (-3200 3600);
FORCEPROP 1 LAST BODY_TYPE PLUMBING
J 0
(-3200 3550);
DISPLAY 1.234043 (-3200 3550);
PAINT GREEN (-3200 3550);
DISPLAY INVISIBLE (-3200 3550);
FORCEPROP 1 LAST HDL_TAP TRUE
J 0
(-2875 3475);
DISPLAY 1.234043 (-2875 3475);
PAINT GREEN (-2875 3475);
DISPLAY INVISIBLE (-2875 3475);
FORCEPROP 1 LAST PATH I134
J 0
(-3200 3600);
DISPLAY 0.936170 (-3200 3600);
PAINT GREEN (-3200 3600);
DISPLAY INVISIBLE (-3200 3600);
FORCEADD OFFPAGE..1
(-3800 3250);
FORCEPROP 2 LAST $XR0 25 
J 0
(-4051 3250);
DISPLAY 0.638298 (-4051 3250);
PAINT MONO (-4051 3250);
FORCEPROP 2 LAST $XR1 48 
J 0
(-4141 3250);
DISPLAY 0.638298 (-4141 3250);
PAINT MONO (-4141 3250);
FORCEPROP 2 LAST CDS_LIB mstr_standard
J 0
(-3800 3250);
DISPLAY 0.787234 (-3800 3250);
PAINT MONO (-3800 3250);
DISPLAY INVISIBLE (-3800 3250);
FORCEPROP 1 LAST OFFPAGE TRUE
J 0
(-3475 3125);
DISPLAY 0.936170 (-3475 3125);
PAINT GREEN (-3475 3125);
DISPLAY INVISIBLE (-3475 3125);
FORCEPROP 1 LAST COMMENT_BODY TRUE
J 0
(-3675 3150);
DISPLAY 0.936170 (-3675 3150);
PAINT GREEN (-3675 3150);
DISPLAY INVISIBLE (-3675 3150);
FORCEPROP 2 LAST PATH I135
J 0
(-3750 3325);
DISPLAY 0.787234 (-3750 3325);
PAINT MONO (-3750 3325);
DISPLAY INVISIBLE (-3750 3325);
FORCEADD OFFPAGE..1
(-3800 3750);
FORCEPROP 2 LAST $XR0 25 
J 0
(-4051 3750);
DISPLAY 0.638298 (-4051 3750);
PAINT MONO (-4051 3750);
FORCEPROP 2 LAST $XR1 48 
J 0
(-4141 3750);
DISPLAY 0.638298 (-4141 3750);
PAINT MONO (-4141 3750);
FORCEPROP 2 LAST CDS_LIB mstr_standard
J 0
(-3800 3750);
DISPLAY 0.787234 (-3800 3750);
PAINT MONO (-3800 3750);
DISPLAY INVISIBLE (-3800 3750);
FORCEPROP 1 LAST OFFPAGE TRUE
J 0
(-3475 3625);
DISPLAY 0.936170 (-3475 3625);
PAINT GREEN (-3475 3625);
DISPLAY INVISIBLE (-3475 3625);
FORCEPROP 1 LAST COMMENT_BODY TRUE
J 0
(-3675 3650);
DISPLAY 0.936170 (-3675 3650);
PAINT GREEN (-3675 3650);
DISPLAY INVISIBLE (-3675 3650);
FORCEPROP 2 LAST PATH I136
J 0
(-3750 3825);
DISPLAY 0.787234 (-3750 3825);
PAINT MONO (-3750 3825);
DISPLAY INVISIBLE (-3750 3825);
FORCEADD OFFPAGE..1
(-3800 3650);
FORCEPROP 2 LAST $XR0 25 
J 0
(-4051 3650);
DISPLAY 0.638298 (-4051 3650);
PAINT MONO (-4051 3650);
FORCEPROP 2 LAST $XR1 48 
J 0
(-4141 3650);
DISPLAY 0.638298 (-4141 3650);
PAINT MONO (-4141 3650);
FORCEPROP 2 LAST CDS_LIB mstr_standard
J 0
(-3800 3650);
DISPLAY 0.787234 (-3800 3650);
PAINT MONO (-3800 3650);
DISPLAY INVISIBLE (-3800 3650);
FORCEPROP 1 LAST OFFPAGE TRUE
J 0
(-3475 3525);
DISPLAY 0.936170 (-3475 3525);
PAINT GREEN (-3475 3525);
DISPLAY INVISIBLE (-3475 3525);
FORCEPROP 1 LAST COMMENT_BODY TRUE
J 0
(-3675 3550);
DISPLAY 0.936170 (-3675 3550);
PAINT GREEN (-3675 3550);
DISPLAY INVISIBLE (-3675 3550);
FORCEPROP 2 LAST PATH I137
J 0
(-3750 3725);
DISPLAY 0.787234 (-3750 3725);
PAINT MONO (-3750 3725);
DISPLAY INVISIBLE (-3750 3725);
FORCEADD TAP..6
(-3200 2600);
FORCEPROP 3 LASTPIN (-3150 2600) SIG_NAME M_C_ECC<6>
J 0
(-3140 2610);
DISPLAY 0.659574 (-3140 2610);
PAINT MONO (-3140 2610);
DISPLAY INVISIBLE (-3140 2610);
FORCEPROP 1 LASTPIN (-3150 2600) BN 6
J 0
(-3200 2610);
DISPLAY 0.617021 (-3200 2610);
PAINT PINK (-3200 2610);
FORCEPROP 2 LAST CDS_LIB mstr_standard
J 0
(-3200 2600);
DISPLAY 0.787234 (-3200 2600);
PAINT MONO (-3200 2600);
DISPLAY INVISIBLE (-3200 2600);
FORCEPROP 1 LAST BODY_TYPE PLUMBING
J 0
(-3200 2550);
DISPLAY 1.234043 (-3200 2550);
PAINT GREEN (-3200 2550);
DISPLAY INVISIBLE (-3200 2550);
FORCEPROP 1 LAST HDL_TAP TRUE
J 0
(-2875 2475);
DISPLAY 1.234043 (-2875 2475);
PAINT GREEN (-2875 2475);
DISPLAY INVISIBLE (-2875 2475);
FORCEPROP 1 LAST PATH I138
J 0
(-3200 2600);
DISPLAY 0.936170 (-3200 2600);
PAINT GREEN (-3200 2600);
DISPLAY INVISIBLE (-3200 2600);
FORCEADD TAP..6
(-3200 2550);
FORCEPROP 3 LASTPIN (-3150 2550) SIG_NAME M_C_ECC<7>
J 0
(-3140 2560);
DISPLAY 0.659574 (-3140 2560);
PAINT MONO (-3140 2560);
DISPLAY INVISIBLE (-3140 2560);
FORCEPROP 1 LASTPIN (-3150 2550) BN 7
J 0
(-3200 2560);
DISPLAY 0.617021 (-3200 2560);
PAINT PINK (-3200 2560);
FORCEPROP 2 LAST CDS_LIB mstr_standard
J 0
(-3200 2550);
DISPLAY 0.787234 (-3200 2550);
PAINT MONO (-3200 2550);
DISPLAY INVISIBLE (-3200 2550);
FORCEPROP 1 LAST BODY_TYPE PLUMBING
J 0
(-3200 2500);
DISPLAY 1.234043 (-3200 2500);
PAINT GREEN (-3200 2500);
DISPLAY INVISIBLE (-3200 2500);
FORCEPROP 1 LAST HDL_TAP TRUE
J 0
(-2875 2425);
DISPLAY 1.234043 (-2875 2425);
PAINT GREEN (-2875 2425);
DISPLAY INVISIBLE (-2875 2425);
FORCEPROP 1 LAST PATH I139
J 0
(-3200 2550);
DISPLAY 0.936170 (-3200 2550);
PAINT GREEN (-3200 2550);
DISPLAY INVISIBLE (-3200 2550);
FORCEADD TAP..6
R 2
(900 4650);
FORCEPROP 3 LASTPIN (850 4650) SIG_NAME M_C_DQS_DN<12>
J 0
(860 4660);
DISPLAY 0.659574 (860 4660);
PAINT MONO (860 4660);
DISPLAY INVISIBLE (860 4660);
FORCEPROP 1 LASTPIN (850 4650) BN 12
J 2
(900 4660);
DISPLAY 0.617021 (900 4660);
PAINT PINK (900 4660);
FORCEPROP 2 LAST CDS_LIB mstr_standard
J 0
(900 4650);
DISPLAY 0.787234 (900 4650);
PAINT MONO (900 4650);
DISPLAY INVISIBLE (900 4650);
FORCEPROP 1 LAST BODY_TYPE PLUMBING
J 2
(900 4600);
DISPLAY 1.234043 (900 4600);
PAINT GREEN (900 4600);
DISPLAY INVISIBLE (900 4600);
FORCEPROP 1 LAST HDL_TAP TRUE
J 2
(575 4525);
DISPLAY 1.234043 (575 4525);
PAINT GREEN (575 4525);
DISPLAY INVISIBLE (575 4525);
FORCEPROP 1 LAST PATH I14
J 2
(900 4650);
DISPLAY 0.936170 (900 4650);
PAINT GREEN (900 4650);
DISPLAY INVISIBLE (900 4650);
FORCEADD TAP..6
(-3200 2500);
FORCEPROP 3 LASTPIN (-3150 2500) SIG_NAME M_C_ECC<4>
J 0
(-3140 2510);
DISPLAY 0.659574 (-3140 2510);
PAINT MONO (-3140 2510);
DISPLAY INVISIBLE (-3140 2510);
FORCEPROP 1 LASTPIN (-3150 2500) BN 4
J 0
(-3200 2510);
DISPLAY 0.617021 (-3200 2510);
PAINT PINK (-3200 2510);
FORCEPROP 2 LAST CDS_LIB mstr_standard
J 0
(-3200 2500);
DISPLAY 0.787234 (-3200 2500);
PAINT MONO (-3200 2500);
DISPLAY INVISIBLE (-3200 2500);
FORCEPROP 1 LAST BODY_TYPE PLUMBING
J 0
(-3200 2450);
DISPLAY 1.234043 (-3200 2450);
PAINT GREEN (-3200 2450);
DISPLAY INVISIBLE (-3200 2450);
FORCEPROP 1 LAST HDL_TAP TRUE
J 0
(-2875 2375);
DISPLAY 1.234043 (-2875 2375);
PAINT GREEN (-2875 2375);
DISPLAY INVISIBLE (-2875 2375);
FORCEPROP 1 LAST PATH I140
J 0
(-3200 2500);
DISPLAY 0.936170 (-3200 2500);
PAINT GREEN (-3200 2500);
DISPLAY INVISIBLE (-3200 2500);
FORCEADD TAP..6
(-3200 2450);
FORCEPROP 3 LASTPIN (-3150 2450) SIG_NAME M_C_ECC<5>
J 0
(-3140 2460);
DISPLAY 0.659574 (-3140 2460);
PAINT MONO (-3140 2460);
DISPLAY INVISIBLE (-3140 2460);
FORCEPROP 1 LASTPIN (-3150 2450) BN 5
J 0
(-3200 2460);
DISPLAY 0.617021 (-3200 2460);
PAINT PINK (-3200 2460);
FORCEPROP 2 LAST CDS_LIB mstr_standard
J 0
(-3200 2450);
DISPLAY 0.787234 (-3200 2450);
PAINT MONO (-3200 2450);
DISPLAY INVISIBLE (-3200 2450);
FORCEPROP 1 LAST BODY_TYPE PLUMBING
J 0
(-3200 2400);
DISPLAY 1.234043 (-3200 2400);
PAINT GREEN (-3200 2400);
DISPLAY INVISIBLE (-3200 2400);
FORCEPROP 1 LAST HDL_TAP TRUE
J 0
(-2875 2325);
DISPLAY 1.234043 (-2875 2325);
PAINT GREEN (-2875 2325);
DISPLAY INVISIBLE (-2875 2325);
FORCEPROP 1 LAST PATH I141
J 0
(-3200 2450);
DISPLAY 0.936170 (-3200 2450);
PAINT GREEN (-3200 2450);
DISPLAY INVISIBLE (-3200 2450);
FORCEADD TAP..6
(-3200 2400);
FORCEPROP 3 LASTPIN (-3150 2400) SIG_NAME M_C_ECC<2>
J 0
(-3140 2410);
DISPLAY 0.659574 (-3140 2410);
PAINT MONO (-3140 2410);
DISPLAY INVISIBLE (-3140 2410);
FORCEPROP 1 LASTPIN (-3150 2400) BN 2
J 0
(-3200 2410);
DISPLAY 0.617021 (-3200 2410);
PAINT PINK (-3200 2410);
FORCEPROP 2 LAST CDS_LIB mstr_standard
J 0
(-3200 2400);
DISPLAY 0.787234 (-3200 2400);
PAINT MONO (-3200 2400);
DISPLAY INVISIBLE (-3200 2400);
FORCEPROP 1 LAST BODY_TYPE PLUMBING
J 0
(-3200 2350);
DISPLAY 1.234043 (-3200 2350);
PAINT GREEN (-3200 2350);
DISPLAY INVISIBLE (-3200 2350);
FORCEPROP 1 LAST HDL_TAP TRUE
J 0
(-2875 2275);
DISPLAY 1.234043 (-2875 2275);
PAINT GREEN (-2875 2275);
DISPLAY INVISIBLE (-2875 2275);
FORCEPROP 1 LAST PATH I142
J 0
(-3200 2400);
DISPLAY 0.936170 (-3200 2400);
PAINT GREEN (-3200 2400);
DISPLAY INVISIBLE (-3200 2400);
FORCEADD TAP..6
(-3200 2350);
FORCEPROP 3 LASTPIN (-3150 2350) SIG_NAME M_C_ECC<3>
J 0
(-3140 2360);
DISPLAY 0.659574 (-3140 2360);
PAINT MONO (-3140 2360);
DISPLAY INVISIBLE (-3140 2360);
FORCEPROP 1 LASTPIN (-3150 2350) BN 3
J 0
(-3200 2360);
DISPLAY 0.617021 (-3200 2360);
PAINT PINK (-3200 2360);
FORCEPROP 2 LAST CDS_LIB mstr_standard
J 0
(-3200 2350);
DISPLAY 0.787234 (-3200 2350);
PAINT MONO (-3200 2350);
DISPLAY INVISIBLE (-3200 2350);
FORCEPROP 1 LAST BODY_TYPE PLUMBING
J 0
(-3200 2300);
DISPLAY 1.234043 (-3200 2300);
PAINT GREEN (-3200 2300);
DISPLAY INVISIBLE (-3200 2300);
FORCEPROP 1 LAST HDL_TAP TRUE
J 0
(-2875 2225);
DISPLAY 1.234043 (-2875 2225);
PAINT GREEN (-2875 2225);
DISPLAY INVISIBLE (-2875 2225);
FORCEPROP 1 LAST PATH I143
J 0
(-3200 2350);
DISPLAY 0.936170 (-3200 2350);
PAINT GREEN (-3200 2350);
DISPLAY INVISIBLE (-3200 2350);
FORCEADD TAP..6
(-3200 2300);
FORCEPROP 3 LASTPIN (-3150 2300) SIG_NAME M_C_ECC<0>
J 0
(-3140 2310);
DISPLAY 0.659574 (-3140 2310);
PAINT MONO (-3140 2310);
DISPLAY INVISIBLE (-3140 2310);
FORCEPROP 1 LASTPIN (-3150 2300) BN 0
J 0
(-3200 2310);
DISPLAY 0.617021 (-3200 2310);
PAINT PINK (-3200 2310);
FORCEPROP 2 LAST CDS_LIB mstr_standard
J 0
(-3200 2300);
DISPLAY 0.787234 (-3200 2300);
PAINT MONO (-3200 2300);
DISPLAY INVISIBLE (-3200 2300);
FORCEPROP 1 LAST BODY_TYPE PLUMBING
J 0
(-3200 2250);
DISPLAY 1.234043 (-3200 2250);
PAINT GREEN (-3200 2250);
DISPLAY INVISIBLE (-3200 2250);
FORCEPROP 1 LAST HDL_TAP TRUE
J 0
(-2875 2175);
DISPLAY 1.234043 (-2875 2175);
PAINT GREEN (-2875 2175);
DISPLAY INVISIBLE (-2875 2175);
FORCEPROP 1 LAST PATH I144
J 0
(-3200 2300);
DISPLAY 0.936170 (-3200 2300);
PAINT GREEN (-3200 2300);
DISPLAY INVISIBLE (-3200 2300);
FORCEADD TAP..6
(-3200 2250);
FORCEPROP 3 LASTPIN (-3150 2250) SIG_NAME M_C_ECC<1>
J 0
(-3140 2260);
DISPLAY 0.659574 (-3140 2260);
PAINT MONO (-3140 2260);
DISPLAY INVISIBLE (-3140 2260);
FORCEPROP 1 LASTPIN (-3150 2250) BN 1
J 0
(-3200 2260);
DISPLAY 0.617021 (-3200 2260);
PAINT PINK (-3200 2260);
FORCEPROP 2 LAST CDS_LIB mstr_standard
J 0
(-3200 2250);
DISPLAY 0.787234 (-3200 2250);
PAINT MONO (-3200 2250);
DISPLAY INVISIBLE (-3200 2250);
FORCEPROP 1 LAST BODY_TYPE PLUMBING
J 0
(-3200 2200);
DISPLAY 1.234043 (-3200 2200);
PAINT GREEN (-3200 2200);
DISPLAY INVISIBLE (-3200 2200);
FORCEPROP 1 LAST HDL_TAP TRUE
J 0
(-2875 2125);
DISPLAY 1.234043 (-2875 2125);
PAINT GREEN (-2875 2125);
DISPLAY INVISIBLE (-2875 2125);
FORCEPROP 1 LAST PATH I145
J 0
(-3200 2250);
DISPLAY 0.936170 (-3200 2250);
PAINT GREEN (-3200 2250);
DISPLAY INVISIBLE (-3200 2250);
FORCEADD OFFPAGE..1
(-3800 2600);
FORCEPROP 2 LAST $XR0 25 
J 0
(-4051 2600);
DISPLAY 0.638298 (-4051 2600);
PAINT MONO (-4051 2600);
FORCEPROP 2 LAST $XR1 48 
J 0
(-4141 2600);
DISPLAY 0.638298 (-4141 2600);
PAINT MONO (-4141 2600);
FORCEPROP 2 LAST CDS_LIB mstr_standard
J 0
(-3800 2600);
DISPLAY 0.787234 (-3800 2600);
PAINT MONO (-3800 2600);
DISPLAY INVISIBLE (-3800 2600);
FORCEPROP 1 LAST OFFPAGE TRUE
J 0
(-3475 2475);
DISPLAY 0.936170 (-3475 2475);
PAINT GREEN (-3475 2475);
DISPLAY INVISIBLE (-3475 2475);
FORCEPROP 1 LAST COMMENT_BODY TRUE
J 0
(-3675 2500);
DISPLAY 0.936170 (-3675 2500);
PAINT GREEN (-3675 2500);
DISPLAY INVISIBLE (-3675 2500);
FORCEPROP 2 LAST PATH I146
J 0
(-3750 2675);
DISPLAY 0.787234 (-3750 2675);
PAINT MONO (-3750 2675);
DISPLAY INVISIBLE (-3750 2675);
FORCEADD OFFPAGE..1
(-3800 2550);
FORCEPROP 2 LAST $XR0 21 
J 0
(-4051 2550);
DISPLAY 0.638298 (-4051 2550);
PAINT MONO (-4051 2550);
FORCEPROP 2 LAST $XR1 43 
J 0
(-4141 2550);
DISPLAY 0.638298 (-4141 2550);
PAINT MONO (-4141 2550);
FORCEPROP 2 LAST $XR2 44 
J 0
(-4231 2550);
DISPLAY 0.638298 (-4231 2550);
PAINT MONO (-4231 2550);
FORCEPROP 2 LAST $XR3 45 
J 0
(-4321 2550);
DISPLAY 0.638298 (-4321 2550);
PAINT MONO (-4321 2550);
FORCEPROP 2 LAST $XR4 46 
J 0
(-4411 2550);
DISPLAY 0.638298 (-4411 2550);
PAINT MONO (-4411 2550);
FORCEPROP 2 LAST $XR5 48 
J 0
(-4501 2550);
DISPLAY 0.638298 (-4501 2550);
PAINT MONO (-4501 2550);
FORCEPROP 2 LAST CDS_LIB mstr_standard
J 0
(-3800 2550);
DISPLAY 0.787234 (-3800 2550);
PAINT MONO (-3800 2550);
DISPLAY INVISIBLE (-3800 2550);
FORCEPROP 1 LAST OFFPAGE TRUE
J 0
(-3475 2425);
DISPLAY 0.936170 (-3475 2425);
PAINT GREEN (-3475 2425);
DISPLAY INVISIBLE (-3475 2425);
FORCEPROP 1 LAST COMMENT_BODY TRUE
J 0
(-3675 2450);
DISPLAY 0.936170 (-3675 2450);
PAINT GREEN (-3675 2450);
DISPLAY INVISIBLE (-3675 2450);
FORCEPROP 2 LAST PATH I147
J 0
(-3750 2625);
DISPLAY 0.787234 (-3750 2625);
PAINT MONO (-3750 2625);
DISPLAY INVISIBLE (-3750 2625);
FORCEADD OFFPAGE..5
(-4025 2000);
FORCEPROP 2 LAST $XR0 48 
J 0
(-4249 2000);
DISPLAY 0.638298 (-4249 2000);
PAINT MONO (-4249 2000);
FORCEPROP 2 LAST $XR1 25 
J 0
(-4339 2000);
DISPLAY 0.638298 (-4339 2000);
PAINT MONO (-4339 2000);
FORCEPROP 2 LAST CDS_LIB mstr_standard
J 0
(-4025 2000);
DISPLAY 0.787234 (-4025 2000);
PAINT MONO (-4025 2000);
DISPLAY INVISIBLE (-4025 2000);
FORCEPROP 1 LAST OFFPAGE TRUE
J 0
(-3700 1875);
DISPLAY 1.404255 (-3700 1875);
PAINT GREEN (-3700 1875);
DISPLAY INVISIBLE (-3700 1875);
FORCEPROP 1 LAST COMMENT_BODY TRUE
J 0
(-3925 1925);
DISPLAY 1.404255 (-3925 1925);
PAINT GREEN (-3925 1925);
DISPLAY INVISIBLE (-3925 1925);
FORCEPROP 2 LAST PATH I148
J 0
(-3975 2075);
DISPLAY 0.787234 (-3975 2075);
PAINT MONO (-3975 2075);
DISPLAY INVISIBLE (-3975 2075);
FORCEADD OFFPAGE..1
(-4000 1950);
FORCEPROP 2 LAST $XR0 25 
J 0
(-4251 1950);
DISPLAY 0.638298 (-4251 1950);
PAINT MONO (-4251 1950);
FORCEPROP 2 LAST $XR1 48 
J 0
(-4341 1950);
DISPLAY 0.638298 (-4341 1950);
PAINT MONO (-4341 1950);
FORCEPROP 2 LAST CDS_LIB mstr_standard
J 0
(-4000 1950);
DISPLAY 0.787234 (-4000 1950);
PAINT MONO (-4000 1950);
DISPLAY INVISIBLE (-4000 1950);
FORCEPROP 1 LAST OFFPAGE TRUE
J 0
(-3675 1825);
DISPLAY 0.936170 (-3675 1825);
PAINT GREEN (-3675 1825);
DISPLAY INVISIBLE (-3675 1825);
FORCEPROP 1 LAST COMMENT_BODY TRUE
J 0
(-3875 1850);
DISPLAY 0.936170 (-3875 1850);
PAINT GREEN (-3875 1850);
DISPLAY INVISIBLE (-3875 1850);
FORCEPROP 2 LAST PATH I149
J 0
(-3950 2025);
DISPLAY 0.787234 (-3950 2025);
PAINT MONO (-3950 2025);
DISPLAY INVISIBLE (-3950 2025);
FORCEADD TAP..6
R 2
(900 4750);
FORCEPROP 3 LASTPIN (850 4750) SIG_NAME M_C_DQS_DN<13>
J 0
(860 4760);
DISPLAY 0.659574 (860 4760);
PAINT MONO (860 4760);
DISPLAY INVISIBLE (860 4760);
FORCEPROP 1 LASTPIN (850 4750) BN 13
J 2
(900 4760);
DISPLAY 0.617021 (900 4760);
PAINT PINK (900 4760);
FORCEPROP 2 LAST CDS_LIB mstr_standard
J 0
(900 4750);
DISPLAY 0.787234 (900 4750);
PAINT MONO (900 4750);
DISPLAY INVISIBLE (900 4750);
FORCEPROP 1 LAST BODY_TYPE PLUMBING
J 2
(900 4700);
DISPLAY 1.234043 (900 4700);
PAINT GREEN (900 4700);
DISPLAY INVISIBLE (900 4700);
FORCEPROP 1 LAST HDL_TAP TRUE
J 2
(575 4625);
DISPLAY 1.234043 (575 4625);
PAINT GREEN (575 4625);
DISPLAY INVISIBLE (575 4625);
FORCEPROP 1 LAST PATH I15
J 2
(900 4750);
DISPLAY 0.936170 (900 4750);
PAINT GREEN (900 4750);
DISPLAY INVISIBLE (900 4750);
FORCEADD OFFPAGE..6
(-3800 2650);
FORCEPROP 2 LAST $XR0 25 
J 0
(-4049 2650);
DISPLAY 0.638298 (-4049 2650);
PAINT MONO (-4049 2650);
FORCEPROP 2 LAST $XR1 48 
J 0
(-4139 2650);
DISPLAY 0.638298 (-4139 2650);
PAINT MONO (-4139 2650);
FORCEPROP 2 LAST CDS_LIB mstr_standard
J 0
(-3800 2650);
DISPLAY 0.787234 (-3800 2650);
PAINT MONO (-3800 2650);
DISPLAY INVISIBLE (-3800 2650);
FORCEPROP 1 LAST OFFPAGE TRUE
J 0
(-3475 2525);
DISPLAY 0.936170 (-3475 2525);
PAINT GREEN (-3475 2525);
DISPLAY INVISIBLE (-3475 2525);
FORCEPROP 1 LAST COMMENT_BODY TRUE
J 0
(-3700 2575);
DISPLAY 0.936170 (-3700 2575);
PAINT GREEN (-3700 2575);
DISPLAY INVISIBLE (-3700 2575);
FORCEPROP 2 LAST PATH I150
J 0
(-3750 2725);
DISPLAY 0.787234 (-3750 2725);
PAINT MONO (-3750 2725);
DISPLAY INVISIBLE (-3750 2725);
FORCEADD OFFPAGE..1
(-4800 1500);
FORCEPROP 2 LAST $XR0 98 
J 0
(-5051 1500);
DISPLAY 0.638298 (-5051 1500);
PAINT MONO (-5051 1500);
FORCEPROP 2 LAST $XR1 48 
J 0
(-5141 1500);
DISPLAY 0.638298 (-5141 1500);
PAINT MONO (-5141 1500);
FORCEPROP 2 LAST CDS_LIB mstr_standard
J 0
(-4800 1500);
DISPLAY 0.787234 (-4800 1500);
PAINT MONO (-4800 1500);
DISPLAY INVISIBLE (-4800 1500);
FORCEPROP 1 LAST OFFPAGE TRUE
J 0
(-4475 1375);
DISPLAY 0.936170 (-4475 1375);
PAINT GREEN (-4475 1375);
DISPLAY INVISIBLE (-4475 1375);
FORCEPROP 1 LAST COMMENT_BODY TRUE
J 0
(-4675 1400);
DISPLAY 0.936170 (-4675 1400);
PAINT GREEN (-4675 1400);
DISPLAY INVISIBLE (-4675 1400);
FORCEPROP 2 LAST PATH I151
J 0
(-4750 1575);
DISPLAY 0.787234 (-4750 1575);
PAINT MONO (-4750 1575);
DISPLAY INVISIBLE (-4750 1575);
FORCEADD TAP..6
(-3200 2700);
FORCEPROP 3 LASTPIN (-3150 2700) SIG_NAME M_C_ODT<0>
J 0
(-3140 2710);
DISPLAY 0.659574 (-3140 2710);
PAINT MONO (-3140 2710);
DISPLAY INVISIBLE (-3140 2710);
FORCEPROP 1 LASTPIN (-3150 2700) BN 0
J 0
(-3200 2710);
DISPLAY 0.617021 (-3200 2710);
PAINT PINK (-3200 2710);
FORCEPROP 2 LAST CDS_LIB mstr_standard
J 0
(-3200 2700);
DISPLAY 0.787234 (-3200 2700);
PAINT MONO (-3200 2700);
DISPLAY INVISIBLE (-3200 2700);
FORCEPROP 1 LAST BODY_TYPE PLUMBING
J 0
(-3200 2650);
DISPLAY 1.234043 (-3200 2650);
PAINT GREEN (-3200 2650);
DISPLAY INVISIBLE (-3200 2650);
FORCEPROP 1 LAST HDL_TAP TRUE
J 0
(-2875 2575);
DISPLAY 1.234043 (-2875 2575);
PAINT GREEN (-2875 2575);
DISPLAY INVISIBLE (-2875 2575);
FORCEPROP 1 LAST PATH I152
J 0
(-3200 2700);
DISPLAY 0.936170 (-3200 2700);
PAINT GREEN (-3200 2700);
DISPLAY INVISIBLE (-3200 2700);
FORCEADD TAP..6
(-3200 2750);
FORCEPROP 3 LASTPIN (-3150 2750) SIG_NAME M_C_ODT<1>
J 0
(-3140 2760);
DISPLAY 0.659574 (-3140 2760);
PAINT MONO (-3140 2760);
DISPLAY INVISIBLE (-3140 2760);
FORCEPROP 1 LASTPIN (-3150 2750) BN 1
J 0
(-3200 2760);
DISPLAY 0.617021 (-3200 2760);
PAINT PINK (-3200 2760);
FORCEPROP 2 LAST CDS_LIB mstr_standard
J 0
(-3200 2750);
DISPLAY 0.787234 (-3200 2750);
PAINT MONO (-3200 2750);
DISPLAY INVISIBLE (-3200 2750);
FORCEPROP 1 LAST BODY_TYPE PLUMBING
J 0
(-3200 2700);
DISPLAY 1.234043 (-3200 2700);
PAINT GREEN (-3200 2700);
DISPLAY INVISIBLE (-3200 2700);
FORCEPROP 1 LAST HDL_TAP TRUE
J 0
(-2875 2625);
DISPLAY 1.234043 (-2875 2625);
PAINT GREEN (-2875 2625);
DISPLAY INVISIBLE (-2875 2625);
FORCEPROP 1 LAST PATH I153
J 0
(-3200 2750);
DISPLAY 0.936170 (-3200 2750);
PAINT GREEN (-3200 2750);
DISPLAY INVISIBLE (-3200 2750);
FORCEADD OFFPAGE..1
(-3800 2850);
FORCEPROP 2 LAST $XR0 25 
J 0
(-4051 2850);
DISPLAY 0.638298 (-4051 2850);
PAINT MONO (-4051 2850);
FORCEPROP 2 LAST $XR1 48 
J 0
(-4141 2850);
DISPLAY 0.638298 (-4141 2850);
PAINT MONO (-4141 2850);
FORCEPROP 2 LAST CDS_LIB mstr_standard
J 0
(-3800 2850);
DISPLAY 0.787234 (-3800 2850);
PAINT MONO (-3800 2850);
DISPLAY INVISIBLE (-3800 2850);
FORCEPROP 1 LAST OFFPAGE TRUE
J 0
(-3475 2725);
DISPLAY 0.936170 (-3475 2725);
PAINT GREEN (-3475 2725);
DISPLAY INVISIBLE (-3475 2725);
FORCEPROP 1 LAST COMMENT_BODY TRUE
J 0
(-3675 2750);
DISPLAY 0.936170 (-3675 2750);
PAINT GREEN (-3675 2750);
DISPLAY INVISIBLE (-3675 2750);
FORCEPROP 2 LAST PATH I154
J 0
(-3750 2925);
DISPLAY 0.787234 (-3750 2925);
PAINT MONO (-3750 2925);
DISPLAY INVISIBLE (-3750 2925);
FORCEADD TAP..6
(-3200 2900);
FORCEPROP 3 LASTPIN (-3150 2900) SIG_NAME M_C_CKE<1>
J 0
(-3140 2910);
DISPLAY 0.659574 (-3140 2910);
PAINT MONO (-3140 2910);
DISPLAY INVISIBLE (-3140 2910);
FORCEPROP 1 LASTPIN (-3150 2900) BN 1
J 0
(-3200 2910);
DISPLAY 0.617021 (-3200 2910);
PAINT PINK (-3200 2910);
FORCEPROP 2 LAST CDS_LIB mstr_standard
J 0
(-3200 2900);
DISPLAY 0.787234 (-3200 2900);
PAINT MONO (-3200 2900);
DISPLAY INVISIBLE (-3200 2900);
FORCEPROP 1 LAST BODY_TYPE PLUMBING
J 0
(-3200 2850);
DISPLAY 1.234043 (-3200 2850);
PAINT GREEN (-3200 2850);
DISPLAY INVISIBLE (-3200 2850);
FORCEPROP 1 LAST HDL_TAP TRUE
J 0
(-2875 2775);
DISPLAY 1.234043 (-2875 2775);
PAINT GREEN (-2875 2775);
DISPLAY INVISIBLE (-2875 2775);
FORCEPROP 1 LAST PATH I155
J 0
(-3200 2900);
DISPLAY 0.936170 (-3200 2900);
PAINT GREEN (-3200 2900);
DISPLAY INVISIBLE (-3200 2900);
FORCEADD TAP..6
(-3200 2850);
FORCEPROP 3 LASTPIN (-3150 2850) SIG_NAME M_C_CKE<0>
J 0
(-3140 2860);
DISPLAY 0.659574 (-3140 2860);
PAINT MONO (-3140 2860);
DISPLAY INVISIBLE (-3140 2860);
FORCEPROP 1 LASTPIN (-3150 2850) BN 0
J 0
(-3200 2860);
DISPLAY 0.617021 (-3200 2860);
PAINT PINK (-3200 2860);
FORCEPROP 2 LAST CDS_LIB mstr_standard
J 0
(-3200 2850);
DISPLAY 0.787234 (-3200 2850);
PAINT MONO (-3200 2850);
DISPLAY INVISIBLE (-3200 2850);
FORCEPROP 1 LAST BODY_TYPE PLUMBING
J 0
(-3200 2800);
DISPLAY 1.234043 (-3200 2800);
PAINT GREEN (-3200 2800);
DISPLAY INVISIBLE (-3200 2800);
FORCEPROP 1 LAST HDL_TAP TRUE
J 0
(-2875 2725);
DISPLAY 1.234043 (-2875 2725);
PAINT GREEN (-2875 2725);
DISPLAY INVISIBLE (-2875 2725);
FORCEPROP 1 LAST PATH I156
J 0
(-3200 2850);
DISPLAY 0.936170 (-3200 2850);
PAINT GREEN (-3200 2850);
DISPLAY INVISIBLE (-3200 2850);
FORCEADD OFFPAGE..1
(-3800 2950);
FORCEPROP 2 LAST $XR0 25 
J 0
(-4051 2950);
DISPLAY 0.638298 (-4051 2950);
PAINT MONO (-4051 2950);
FORCEPROP 2 LAST $XR1 48 
J 0
(-4141 2950);
DISPLAY 0.638298 (-4141 2950);
PAINT MONO (-4141 2950);
FORCEPROP 2 LAST CDS_LIB mstr_standard
J 0
(-3800 2950);
DISPLAY 0.787234 (-3800 2950);
PAINT MONO (-3800 2950);
DISPLAY INVISIBLE (-3800 2950);
FORCEPROP 1 LAST OFFPAGE TRUE
J 0
(-3475 2825);
DISPLAY 0.936170 (-3475 2825);
PAINT GREEN (-3475 2825);
DISPLAY INVISIBLE (-3475 2825);
FORCEPROP 1 LAST COMMENT_BODY TRUE
J 0
(-3675 2850);
DISPLAY 0.936170 (-3675 2850);
PAINT GREEN (-3675 2850);
DISPLAY INVISIBLE (-3675 2850);
FORCEPROP 2 LAST PATH I157
J 0
(-3750 3025);
DISPLAY 0.787234 (-3750 3025);
PAINT MONO (-3750 3025);
DISPLAY INVISIBLE (-3750 3025);
FORCEADD TAP..6
(-3200 3150);
FORCEPROP 3 LASTPIN (-3150 3150) SIG_NAME M_C_CS_N<3>
J 0
(-3140 3160);
DISPLAY 0.659574 (-3140 3160);
PAINT MONO (-3140 3160);
DISPLAY INVISIBLE (-3140 3160);
FORCEPROP 1 LASTPIN (-3150 3150) BN 3
J 0
(-3200 3160);
DISPLAY 0.617021 (-3200 3160);
PAINT PINK (-3200 3160);
FORCEPROP 2 LAST CDS_LIB mstr_standard
J 0
(-3200 3150);
DISPLAY 0.787234 (-3200 3150);
PAINT MONO (-3200 3150);
DISPLAY INVISIBLE (-3200 3150);
FORCEPROP 1 LAST BODY_TYPE PLUMBING
J 0
(-3200 3100);
DISPLAY 1.234043 (-3200 3100);
PAINT GREEN (-3200 3100);
DISPLAY INVISIBLE (-3200 3100);
FORCEPROP 1 LAST HDL_TAP TRUE
J 0
(-2875 3025);
DISPLAY 1.234043 (-2875 3025);
PAINT GREEN (-2875 3025);
DISPLAY INVISIBLE (-2875 3025);
FORCEPROP 1 LAST PATH I158
J 0
(-3200 3150);
DISPLAY 0.936170 (-3200 3150);
PAINT GREEN (-3200 3150);
DISPLAY INVISIBLE (-3200 3150);
FORCEADD OFFPAGE..1
(-3800 3200);
FORCEPROP 2 LAST $XR0 25 
J 0
(-4051 3200);
DISPLAY 0.638298 (-4051 3200);
PAINT MONO (-4051 3200);
FORCEPROP 2 LAST $XR1 48 
J 0
(-4141 3200);
DISPLAY 0.638298 (-4141 3200);
PAINT MONO (-4141 3200);
FORCEPROP 2 LAST CDS_LIB mstr_standard
J 0
(-3800 3200);
DISPLAY 0.787234 (-3800 3200);
PAINT MONO (-3800 3200);
DISPLAY INVISIBLE (-3800 3200);
FORCEPROP 1 LAST OFFPAGE TRUE
J 0
(-3475 3075);
DISPLAY 0.936170 (-3475 3075);
PAINT GREEN (-3475 3075);
DISPLAY INVISIBLE (-3475 3075);
FORCEPROP 1 LAST COMMENT_BODY TRUE
J 0
(-3675 3100);
DISPLAY 0.936170 (-3675 3100);
PAINT GREEN (-3675 3100);
DISPLAY INVISIBLE (-3675 3100);
FORCEPROP 2 LAST PATH I159
J 0
(-3750 3275);
DISPLAY 0.787234 (-3750 3275);
PAINT MONO (-3750 3275);
DISPLAY INVISIBLE (-3750 3275);
FORCEADD TAP..6
R 2
(700 4800);
FORCEPROP 3 LASTPIN (650 4800) SIG_NAME M_C_DQS_DP<13>
J 0
(660 4810);
DISPLAY 0.659574 (660 4810);
PAINT MONO (660 4810);
DISPLAY INVISIBLE (660 4810);
FORCEPROP 1 LASTPIN (650 4800) BN 13
J 2
(700 4810);
DISPLAY 0.617021 (700 4810);
PAINT PINK (700 4810);
FORCEPROP 2 LAST CDS_LIB mstr_standard
J 0
(700 4800);
DISPLAY 0.787234 (700 4800);
PAINT MONO (700 4800);
DISPLAY INVISIBLE (700 4800);
FORCEPROP 1 LAST BODY_TYPE PLUMBING
J 2
(700 4750);
DISPLAY 1.234043 (700 4750);
PAINT GREEN (700 4750);
DISPLAY INVISIBLE (700 4750);
FORCEPROP 1 LAST HDL_TAP TRUE
J 2
(375 4675);
DISPLAY 1.234043 (375 4675);
PAINT GREEN (375 4675);
DISPLAY INVISIBLE (375 4675);
FORCEPROP 1 LAST PATH I16
J 2
(700 4800);
DISPLAY 0.936170 (700 4800);
PAINT GREEN (700 4800);
DISPLAY INVISIBLE (700 4800);
FORCEADD TAP..6
(-3200 3100);
FORCEPROP 3 LASTPIN (-3150 3100) SIG_NAME M_C_CS_N<2>
J 0
(-3140 3110);
DISPLAY 0.659574 (-3140 3110);
PAINT MONO (-3140 3110);
DISPLAY INVISIBLE (-3140 3110);
FORCEPROP 1 LASTPIN (-3150 3100) BN 2
J 0
(-3200 3110);
DISPLAY 0.617021 (-3200 3110);
PAINT PINK (-3200 3110);
FORCEPROP 2 LAST CDS_LIB mstr_standard
J 0
(-3200 3100);
DISPLAY 0.787234 (-3200 3100);
PAINT MONO (-3200 3100);
DISPLAY INVISIBLE (-3200 3100);
FORCEPROP 1 LAST BODY_TYPE PLUMBING
J 0
(-3200 3050);
DISPLAY 1.234043 (-3200 3050);
PAINT GREEN (-3200 3050);
DISPLAY INVISIBLE (-3200 3050);
FORCEPROP 1 LAST HDL_TAP TRUE
J 0
(-2875 2975);
DISPLAY 1.234043 (-2875 2975);
PAINT GREEN (-2875 2975);
DISPLAY INVISIBLE (-2875 2975);
FORCEPROP 1 LAST PATH I160
J 0
(-3200 3100);
DISPLAY 0.936170 (-3200 3100);
PAINT GREEN (-3200 3100);
DISPLAY INVISIBLE (-3200 3100);
FORCEADD TAP..6
(-3200 3050);
FORCEPROP 3 LASTPIN (-3150 3050) SIG_NAME M_C_CS_N<1>
J 0
(-3140 3060);
DISPLAY 0.659574 (-3140 3060);
PAINT MONO (-3140 3060);
DISPLAY INVISIBLE (-3140 3060);
FORCEPROP 1 LASTPIN (-3150 3050) BN 1
J 0
(-3200 3060);
DISPLAY 0.617021 (-3200 3060);
PAINT PINK (-3200 3060);
FORCEPROP 2 LAST CDS_LIB mstr_standard
J 0
(-3200 3050);
DISPLAY 0.787234 (-3200 3050);
PAINT MONO (-3200 3050);
DISPLAY INVISIBLE (-3200 3050);
FORCEPROP 1 LAST BODY_TYPE PLUMBING
J 0
(-3200 3000);
DISPLAY 1.234043 (-3200 3000);
PAINT GREEN (-3200 3000);
DISPLAY INVISIBLE (-3200 3000);
FORCEPROP 1 LAST HDL_TAP TRUE
J 0
(-2875 2925);
DISPLAY 1.234043 (-2875 2925);
PAINT GREEN (-2875 2925);
DISPLAY INVISIBLE (-2875 2925);
FORCEPROP 1 LAST PATH I161
J 0
(-3200 3050);
DISPLAY 0.936170 (-3200 3050);
PAINT GREEN (-3200 3050);
DISPLAY INVISIBLE (-3200 3050);
FORCEADD TAP..6
(-3200 3000);
FORCEPROP 3 LASTPIN (-3150 3000) SIG_NAME M_C_CS_N<0>
J 0
(-3140 3010);
DISPLAY 0.659574 (-3140 3010);
PAINT MONO (-3140 3010);
DISPLAY INVISIBLE (-3140 3010);
FORCEPROP 1 LASTPIN (-3150 3000) BN 0
J 0
(-3200 3010);
DISPLAY 0.617021 (-3200 3010);
PAINT PINK (-3200 3010);
FORCEPROP 2 LAST CDS_LIB mstr_standard
J 0
(-3200 3000);
DISPLAY 0.787234 (-3200 3000);
PAINT MONO (-3200 3000);
DISPLAY INVISIBLE (-3200 3000);
FORCEPROP 1 LAST BODY_TYPE PLUMBING
J 0
(-3200 2950);
DISPLAY 1.234043 (-3200 2950);
PAINT GREEN (-3200 2950);
DISPLAY INVISIBLE (-3200 2950);
FORCEPROP 1 LAST HDL_TAP TRUE
J 0
(-2875 2875);
DISPLAY 1.234043 (-2875 2875);
PAINT GREEN (-2875 2875);
DISPLAY INVISIBLE (-2875 2875);
FORCEPROP 1 LAST PATH I162
J 0
(-3200 3000);
DISPLAY 0.936170 (-3200 3000);
PAINT GREEN (-3200 3000);
DISPLAY INVISIBLE (-3200 3000);
FORCEADD TAP..6
R 2
(700 4700);
FORCEPROP 3 LASTPIN (650 4700) SIG_NAME M_C_DQS_DP<12>
J 0
(660 4710);
DISPLAY 0.659574 (660 4710);
PAINT MONO (660 4710);
DISPLAY INVISIBLE (660 4710);
FORCEPROP 1 LASTPIN (650 4700) BN 12
J 2
(700 4710);
DISPLAY 0.617021 (700 4710);
PAINT PINK (700 4710);
FORCEPROP 2 LAST CDS_LIB mstr_standard
J 0
(700 4700);
DISPLAY 0.787234 (700 4700);
PAINT MONO (700 4700);
DISPLAY INVISIBLE (700 4700);
FORCEPROP 1 LAST BODY_TYPE PLUMBING
J 2
(700 4650);
DISPLAY 1.234043 (700 4650);
PAINT GREEN (700 4650);
DISPLAY INVISIBLE (700 4650);
FORCEPROP 1 LAST HDL_TAP TRUE
J 2
(375 4575);
DISPLAY 1.234043 (375 4575);
PAINT GREEN (375 4575);
DISPLAY INVISIBLE (375 4575);
FORCEPROP 1 LAST PATH I17
J 2
(700 4700);
DISPLAY 0.936170 (700 4700);
PAINT GREEN (700 4700);
DISPLAY INVISIBLE (700 4700);
FORCEADD TAP..6
(-3750 3300);
FORCEPROP 3 LASTPIN (-3700 3300) SIG_NAME M_C_CLK_DN<0>
J 0
(-3690 3310);
DISPLAY 0.659574 (-3690 3310);
PAINT MONO (-3690 3310);
DISPLAY INVISIBLE (-3690 3310);
FORCEPROP 1 LASTPIN (-3700 3300) BN 0
J 0
(-3750 3310);
DISPLAY 0.617021 (-3750 3310);
PAINT PINK (-3750 3310);
FORCEPROP 2 LAST CDS_LIB mstr_standard
J 0
(-3750 3300);
DISPLAY 0.787234 (-3750 3300);
PAINT MONO (-3750 3300);
DISPLAY INVISIBLE (-3750 3300);
FORCEPROP 1 LAST BODY_TYPE PLUMBING
J 0
(-3750 3250);
DISPLAY 1.234043 (-3750 3250);
PAINT GREEN (-3750 3250);
DISPLAY INVISIBLE (-3750 3250);
FORCEPROP 1 LAST HDL_TAP TRUE
J 0
(-3425 3175);
DISPLAY 1.234043 (-3425 3175);
PAINT GREEN (-3425 3175);
DISPLAY INVISIBLE (-3425 3175);
FORCEPROP 1 LAST PATH I174
J 0
(-3750 3300);
DISPLAY 0.936170 (-3750 3300);
PAINT GREEN (-3750 3300);
DISPLAY INVISIBLE (-3750 3300);
FORCEADD TAP..6
(-3600 3350);
FORCEPROP 3 LASTPIN (-3550 3350) SIG_NAME M_C_CLK_DP<0>
J 0
(-3540 3360);
DISPLAY 0.659574 (-3540 3360);
PAINT MONO (-3540 3360);
DISPLAY INVISIBLE (-3540 3360);
FORCEPROP 1 LASTPIN (-3550 3350) BN 0
J 0
(-3600 3360);
DISPLAY 0.617021 (-3600 3360);
PAINT PINK (-3600 3360);
FORCEPROP 2 LAST CDS_LIB mstr_standard
J 0
(-3600 3350);
DISPLAY 0.787234 (-3600 3350);
PAINT MONO (-3600 3350);
DISPLAY INVISIBLE (-3600 3350);
FORCEPROP 1 LAST BODY_TYPE PLUMBING
J 0
(-3600 3300);
DISPLAY 1.234043 (-3600 3300);
PAINT GREEN (-3600 3300);
DISPLAY INVISIBLE (-3600 3300);
FORCEPROP 1 LAST HDL_TAP TRUE
J 0
(-3275 3225);
DISPLAY 1.234043 (-3275 3225);
PAINT GREEN (-3275 3225);
DISPLAY INVISIBLE (-3275 3225);
FORCEPROP 1 LAST PATH I175
J 0
(-3600 3350);
DISPLAY 0.936170 (-3600 3350);
PAINT GREEN (-3600 3350);
DISPLAY INVISIBLE (-3600 3350);
FORCEADD OFFPAGE..1
(-4300 3500);
FORCEPROP 2 LAST $XR0 25 
J 0
(-4521 3500);
DISPLAY 0.638298 (-4521 3500);
PAINT MONO (-4521 3500);
FORCEPROP 2 LAST $XR1 48 
J 0
(-4611 3500);
DISPLAY 0.638298 (-4611 3500);
PAINT MONO (-4611 3500);
FORCEPROP 2 LAST CDS_LIB mstr_standard
J 0
(-4300 3500);
DISPLAY 0.787234 (-4300 3500);
PAINT MONO (-4300 3500);
DISPLAY INVISIBLE (-4300 3500);
FORCEPROP 1 LAST OFFPAGE TRUE
J 0
(-3975 3375);
DISPLAY 0.936170 (-3975 3375);
PAINT GREEN (-3975 3375);
DISPLAY INVISIBLE (-3975 3375);
FORCEPROP 1 LAST COMMENT_BODY TRUE
J 0
(-4175 3400);
DISPLAY 0.936170 (-4175 3400);
PAINT GREEN (-4175 3400);
DISPLAY INVISIBLE (-4175 3400);
FORCEPROP 2 LAST PATH I177
J 0
(-4250 3575);
DISPLAY 0.787234 (-4250 3575);
PAINT MONO (-4250 3575);
DISPLAY INVISIBLE (-4250 3575);
FORCEADD OFFPAGE..1
(-4300 3550);
FORCEPROP 2 LAST $XR0 25 
J 0
(-4521 3550);
DISPLAY 0.638298 (-4521 3550);
PAINT MONO (-4521 3550);
FORCEPROP 2 LAST $XR1 48 
J 0
(-4611 3550);
DISPLAY 0.638298 (-4611 3550);
PAINT MONO (-4611 3550);
FORCEPROP 2 LAST CDS_LIB mstr_standard
J 0
(-4300 3550);
DISPLAY 0.787234 (-4300 3550);
PAINT MONO (-4300 3550);
DISPLAY INVISIBLE (-4300 3550);
FORCEPROP 1 LAST OFFPAGE TRUE
J 0
(-3975 3425);
DISPLAY 0.936170 (-3975 3425);
PAINT GREEN (-3975 3425);
DISPLAY INVISIBLE (-3975 3425);
FORCEPROP 1 LAST COMMENT_BODY TRUE
J 0
(-4175 3450);
DISPLAY 0.936170 (-4175 3450);
PAINT GREEN (-4175 3450);
DISPLAY INVISIBLE (-4175 3450);
FORCEPROP 2 LAST PATH I178
J 0
(-4250 3625);
DISPLAY 0.787234 (-4250 3625);
PAINT MONO (-4250 3625);
DISPLAY INVISIBLE (-4250 3625);
FORCEADD SCONN288_H44441004..4
(0 2050);
FORCEPROP 1 LAST LOCATION J4G3
J 0
(-450 3150);
DISPLAY 0.617021 (-450 3150);
PAINT AQUA (-450 3150);
FORCEPROP 1 LAST PART_NUMBER H44441-004
J 0
(-450 1000);
DISPLAY 0.617021 (-450 1000);
PAINT BLUE (-450 1000);
FORCEPROP 1 LAST MATERIAL SCONN
J 0
(-450 3100);
DISPLAY 0.617021 (-450 3100);
PAINT SKYBLUE (-450 3100);
FORCEPROP 2 LASTPIN (-500 2600) $PN 77
J 2
(-510 2610);
DISPLAY 0.617021 (-510 2610);
PAINT ORANGE (-510 2610);
FORCEPROP 2 LASTPIN (-500 2550) $PN 221
J 2
(-510 2560);
DISPLAY 0.617021 (-510 2560);
PAINT ORANGE (-510 2560);
FORCEPROP 2 LASTPIN (-500 2900) $PN 142
J 2
(-510 2910);
DISPLAY 0.617021 (-510 2910);
PAINT ORANGE (-510 2910);
FORCEPROP 2 LASTPIN (-500 2850) $PN 143
J 2
(-510 2860);
DISPLAY 0.617021 (-510 2860);
PAINT ORANGE (-510 2860);
FORCEPROP 2 LASTPIN (-500 2800) $PN 288
J 2
(-510 2810);
DISPLAY 0.617021 (-510 2810);
PAINT ORANGE (-510 2810);
FORCEPROP 2 LASTPIN (-500 2750) $PN 286
J 2
(-510 2760);
DISPLAY 0.617021 (-510 2760);
PAINT ORANGE (-510 2760);
FORCEPROP 2 LASTPIN (-500 2700) $PN 287
J 2
(-510 2710);
DISPLAY 0.617021 (-510 2710);
PAINT ORANGE (-510 2710);
FORCEPROP 2 LASTPIN (-500 2450) $PN 59
J 2
(-510 2460);
DISPLAY 0.617021 (-510 2460);
PAINT ORANGE (-510 2460);
FORCEPROP 2 LASTPIN (-500 2400) $PN 61
J 2
(-510 2410);
DISPLAY 0.617021 (-510 2410);
PAINT ORANGE (-510 2410);
FORCEPROP 2 LASTPIN (-500 2350) $PN 64
J 2
(-510 2360);
DISPLAY 0.617021 (-510 2360);
PAINT ORANGE (-510 2360);
FORCEPROP 2 LASTPIN (-500 2300) $PN 67
J 2
(-510 2310);
DISPLAY 0.617021 (-510 2310);
PAINT ORANGE (-510 2310);
FORCEPROP 2 LASTPIN (-500 2250) $PN 70
J 2
(-510 2260);
DISPLAY 0.617021 (-510 2260);
PAINT ORANGE (-510 2260);
FORCEPROP 2 LASTPIN (-500 2200) $PN 73
J 2
(-510 2210);
DISPLAY 0.617021 (-510 2210);
PAINT ORANGE (-510 2210);
FORCEPROP 2 LASTPIN (-500 2150) $PN 76
J 2
(-510 2160);
DISPLAY 0.617021 (-510 2160);
PAINT ORANGE (-510 2160);
FORCEPROP 2 LASTPIN (-500 2100) $PN 80
J 2
(-510 2110);
DISPLAY 0.617021 (-510 2110);
PAINT ORANGE (-510 2110);
FORCEPROP 2 LASTPIN (-500 2050) $PN 83
J 2
(-510 2060);
DISPLAY 0.617021 (-510 2060);
PAINT ORANGE (-510 2060);
FORCEPROP 2 LASTPIN (-500 2000) $PN 85
J 2
(-510 2010);
DISPLAY 0.617021 (-510 2010);
PAINT ORANGE (-510 2010);
FORCEPROP 2 LASTPIN (-500 1950) $PN 88
J 2
(-510 1960);
DISPLAY 0.617021 (-510 1960);
PAINT ORANGE (-510 1960);
FORCEPROP 2 LASTPIN (-500 1900) $PN 90
J 2
(-510 1910);
DISPLAY 0.617021 (-510 1910);
PAINT ORANGE (-510 1910);
FORCEPROP 2 LASTPIN (-500 1850) $PN 92
J 2
(-510 1860);
DISPLAY 0.617021 (-510 1860);
PAINT ORANGE (-510 1860);
FORCEPROP 2 LASTPIN (-500 1800) $PN 204
J 2
(-510 1810);
DISPLAY 0.617021 (-510 1810);
PAINT ORANGE (-510 1810);
FORCEPROP 2 LASTPIN (-500 1750) $PN 206
J 2
(-510 1760);
DISPLAY 0.617021 (-510 1760);
PAINT ORANGE (-510 1760);
FORCEPROP 2 LASTPIN (-500 1700) $PN 209
J 2
(-510 1710);
DISPLAY 0.617021 (-510 1710);
PAINT ORANGE (-510 1710);
FORCEPROP 2 LASTPIN (-500 1650) $PN 212
J 2
(-510 1660);
DISPLAY 0.617021 (-510 1660);
PAINT ORANGE (-510 1660);
FORCEPROP 2 LASTPIN (-500 1600) $PN 215
J 2
(-510 1610);
DISPLAY 0.617021 (-510 1610);
PAINT ORANGE (-510 1610);
FORCEPROP 2 LASTPIN (-500 1550) $PN 217
J 2
(-510 1560);
DISPLAY 0.617021 (-510 1560);
PAINT ORANGE (-510 1560);
FORCEPROP 2 LASTPIN (-500 1500) $PN 220
J 2
(-510 1510);
DISPLAY 0.617021 (-510 1510);
PAINT ORANGE (-510 1510);
FORCEPROP 2 LASTPIN (-500 1450) $PN 223
J 2
(-510 1460);
DISPLAY 0.617021 (-510 1460);
PAINT ORANGE (-510 1460);
FORCEPROP 2 LASTPIN (-500 1400) $PN 226
J 2
(-510 1410);
DISPLAY 0.617021 (-510 1410);
PAINT ORANGE (-510 1410);
FORCEPROP 2 LASTPIN (-500 1350) $PN 229
J 2
(-510 1360);
DISPLAY 0.617021 (-510 1360);
PAINT ORANGE (-510 1360);
FORCEPROP 2 LASTPIN (-500 1300) $PN 231
J 2
(-510 1310);
DISPLAY 0.617021 (-510 1310);
PAINT ORANGE (-510 1310);
FORCEPROP 2 LASTPIN (-500 1250) $PN 233
J 2
(-510 1260);
DISPLAY 0.617021 (-510 1260);
PAINT ORANGE (-510 1260);
FORCEPROP 2 LASTPIN (-500 1200) $PN 236
J 2
(-510 1210);
DISPLAY 0.617021 (-510 1210);
PAINT ORANGE (-510 1210);
FORCEPROP 2 LASTPIN (500 2900) $PN 1
J 0
(510 2910);
DISPLAY 0.617021 (510 2910);
PAINT ORANGE (510 2910);
FORCEPROP 2 LASTPIN (500 2850) $PN 145
J 0
(510 2860);
DISPLAY 0.617021 (510 2860);
PAINT ORANGE (510 2860);
FORCEPROP 1 LAST PACK_TYPE PIP
J 0
(-450 3200);
PAINT SKYBLUE (-450 3200);
DISPLAY INVISIBLE (-450 3200);
FORCEPROP 2 LAST BOM_COST MEM
J 0
(0 2050);
PAINT ORANGE (0 2050);
DISPLAY INVISIBLE (0 2050);
FORCEPROP 2 LAST CDS_LIB mstr_sconn
J 0
(0 2050);
PAINT ORANGE (0 2050);
DISPLAY INVISIBLE (0 2050);
FORCEPROP 2 LAST SEC_TYPE PIP
J 0
(-450 3200);
DISPLAY 1.021277 (-450 3200);
PAINT ORANGE (-450 3200);
DISPLAY INVISIBLE (-450 3200);
FORCEPROP 2 LAST SEC 4
J 0
(-450 3200);
DISPLAY 0.680851 (-450 3200);
PAINT MONO (-450 3200);
DISPLAY INVISIBLE (-450 3200);
FORCEPROP 2 LAST CDS_LOCATION J4G3
J 0
(-450 3150);
DISPLAY 0.617021 (-450 3150);
PAINT AQUA (-450 3150);
DISPLAY INVISIBLE (-450 3150);
FORCEPROP 1 LAST PATH I179
J 0
(0 3100);
PAINT GREEN (0 3100);
DISPLAY INVISIBLE (0 3100);
FORCEPROP 2 LAST ROOM DDR4_CH_C
J 0
(-450 3250);
PAINT ORANGE (-450 3250);
DISPLAY INVISIBLE (-450 3250);
FORCEADD TAP..6
R 2
(700 4600);
FORCEPROP 3 LASTPIN (650 4600) SIG_NAME M_C_DQS_DP<11>
J 0
(660 4610);
DISPLAY 0.659574 (660 4610);
PAINT MONO (660 4610);
DISPLAY INVISIBLE (660 4610);
FORCEPROP 1 LASTPIN (650 4600) BN 11
J 2
(700 4610);
DISPLAY 0.617021 (700 4610);
PAINT PINK (700 4610);
FORCEPROP 2 LAST CDS_LIB mstr_standard
J 0
(700 4600);
DISPLAY 0.787234 (700 4600);
PAINT MONO (700 4600);
DISPLAY INVISIBLE (700 4600);
FORCEPROP 1 LAST BODY_TYPE PLUMBING
J 2
(700 4550);
DISPLAY 1.234043 (700 4550);
PAINT GREEN (700 4550);
DISPLAY INVISIBLE (700 4550);
FORCEPROP 1 LAST HDL_TAP TRUE
J 2
(375 4475);
DISPLAY 1.234043 (375 4475);
PAINT GREEN (375 4475);
DISPLAY INVISIBLE (375 4475);
FORCEPROP 1 LAST PATH I18
J 2
(700 4600);
DISPLAY 0.936170 (700 4600);
PAINT GREEN (700 4600);
DISPLAY INVISIBLE (700 4600);
FORCEADD GND..1
R 2
(2500 1350);
FORCEPROP 3 LASTPIN (2500 1400) SIG_NAME GND\g
J 0
(2510 1410);
DISPLAY 0.659574 (2510 1410);
PAINT MONO (2510 1410);
DISPLAY INVISIBLE (2510 1410);
FORCEPROP 1 LAST VOLTAGE 0
J 0
(2500 1350);
PAINT SKYBLUE (2500 1350);
DISPLAY INVISIBLE (2500 1350);
FORCEPROP 1 LAST SIZE 1B
J 2
(2425 1300);
DISPLAY 1.170213 (2425 1300);
PAINT GREEN (2425 1300);
DISPLAY INVISIBLE (2425 1300);
FORCEPROP 2 LAST CDS_LIB mstr_symbols
J 0
(2500 1350);
DISPLAY 0.787234 (2500 1350);
PAINT MONO (2500 1350);
DISPLAY INVISIBLE (2500 1350);
FORCEPROP 2 LAST BOM_COST MEM
J 0
(2500 1355);
PAINT ORANGE (2500 1355);
DISPLAY INVISIBLE (2500 1355);
FORCEPROP 1 LAST BODY_TYPE PLUMBING
J 2
(2545 1307);
DISPLAY 0.340426 (2545 1307);
PAINT GREEN (2545 1307);
DISPLAY INVISIBLE (2545 1307);
FORCEPROP 1 LAST PATH I180
J 2
(2425 1350);
DISPLAY 1.404255 (2425 1350);
PAINT GREEN (2425 1350);
DISPLAY INVISIBLE (2425 1350);
FORCEPROP 2 LAST ROOM DDR4_CH_A
J 0
(2500 1355);
PAINT ORANGE (2500 1355);
DISPLAY INVISIBLE (2500 1355);
FORCEPROP 1 LAST HDL_POWER GND
J 2
(2500 1500);
DISPLAY 0.553191 (2500 1500);
PAINT GREEN (2500 1500);
DISPLAY INVISIBLE (2500 1500);
FORCEADD OFFPAGE..5
(-4175 2300);
FORCEPROP 2 LAST $XR0 43 
J 0
(-4429 2300);
DISPLAY 0.638298 (-4429 2300);
PAINT MONO (-4429 2300);
FORCEPROP 2 LAST $XR1 44 
J 0
(-4519 2300);
DISPLAY 0.638298 (-4519 2300);
PAINT MONO (-4519 2300);
FORCEPROP 2 LAST $XR2 45 
J 0
(-4609 2300);
DISPLAY 0.638298 (-4609 2300);
PAINT MONO (-4609 2300);
FORCEPROP 2 LAST $XR3 46 
J 0
(-4699 2300);
DISPLAY 0.638298 (-4699 2300);
PAINT MONO (-4699 2300);
FORCEPROP 2 LAST $XR4 48 
J 0
(-4789 2300);
DISPLAY 0.638298 (-4789 2300);
PAINT MONO (-4789 2300);
FORCEPROP 2 LAST $XR5 49 
J 0
(-4879 2300);
DISPLAY 0.638298 (-4879 2300);
PAINT MONO (-4879 2300);
FORCEPROP 2 LAST $XR6 50 
J 0
(-4969 2300);
DISPLAY 0.638298 (-4969 2300);
PAINT MONO (-4969 2300);
FORCEPROP 2 LAST $XR7 51 
J 0
(-5059 2300);
DISPLAY 0.638298 (-5059 2300);
PAINT MONO (-5059 2300);
FORCEPROP 2 LAST $XR8 52 
J 0
(-5149 2300);
DISPLAY 0.638298 (-5149 2300);
PAINT MONO (-5149 2300);
FORCEPROP 2 LAST $XR9 53 
J 0
(-5239 2300);
DISPLAY 0.638298 (-5239 2300);
PAINT MONO (-5239 2300);
FORCEPROP 2 LAST $XR10 54 
J 0
(-4429 2264);
DISPLAY 0.638298 (-4429 2264);
PAINT MONO (-4429 2264);
FORCEPROP 2 LAST $XR11 77 
J 0
(-4519 2264);
DISPLAY 0.638298 (-4519 2264);
PAINT MONO (-4519 2264);
FORCEPROP 2 LAST $XR12 78 
J 0
(-4609 2264);
DISPLAY 0.638298 (-4609 2264);
PAINT MONO (-4609 2264);
FORCEPROP 2 LAST $XR13 79 
J 0
(-4699 2264);
DISPLAY 0.638298 (-4699 2264);
PAINT MONO (-4699 2264);
FORCEPROP 2 LAST $XR14 80 
J 0
(-4789 2264);
DISPLAY 0.638298 (-4789 2264);
PAINT MONO (-4789 2264);
FORCEPROP 2 LAST $XR15 81 
J 0
(-4879 2264);
DISPLAY 0.638298 (-4879 2264);
PAINT MONO (-4879 2264);
FORCEPROP 2 LAST $XR16 82 
J 0
(-4969 2264);
DISPLAY 0.638298 (-4969 2264);
PAINT MONO (-4969 2264);
FORCEPROP 2 LAST $XR17 83 
J 0
(-5059 2264);
DISPLAY 0.638298 (-5059 2264);
PAINT MONO (-5059 2264);
FORCEPROP 2 LAST $XR18 84 
J 0
(-5149 2264);
DISPLAY 0.638298 (-5149 2264);
PAINT MONO (-5149 2264);
FORCEPROP 2 LAST $XR19 85 
J 0
(-4429 2336);
DISPLAY 0.638298 (-4429 2336);
PAINT MONO (-4429 2336);
FORCEPROP 2 LAST $XR20 86 
J 0
(-4519 2336);
DISPLAY 0.638298 (-4519 2336);
PAINT MONO (-4519 2336);
FORCEPROP 2 LAST $XR21 87 
J 0
(-4609 2336);
DISPLAY 0.638298 (-4609 2336);
PAINT MONO (-4609 2336);
FORCEPROP 2 LAST $XR22 88 
J 0
(-4699 2336);
DISPLAY 0.638298 (-4699 2336);
PAINT MONO (-4699 2336);
FORCEPROP 2 LAST $XR23 94 
J 0
(-4789 2336);
DISPLAY 0.638298 (-4789 2336);
PAINT MONO (-4789 2336);
FORCEPROP 2 LAST CDS_LIB mstr_standard
J 0
(-4175 2300);
DISPLAY 0.787234 (-4175 2300);
PAINT MONO (-4175 2300);
DISPLAY INVISIBLE (-4175 2300);
FORCEPROP 1 LAST OFFPAGE TRUE
J 0
(-3850 2175);
DISPLAY 1.404255 (-3850 2175);
PAINT GREEN (-3850 2175);
DISPLAY INVISIBLE (-3850 2175);
FORCEPROP 1 LAST COMMENT_BODY TRUE
J 0
(-4075 2225);
DISPLAY 1.404255 (-4075 2225);
PAINT GREEN (-4075 2225);
DISPLAY INVISIBLE (-4075 2225);
FORCEPROP 2 LAST PATH I183
J 0
(-4125 2375);
DISPLAY 0.787234 (-4125 2375);
PAINT ORANGE (-4125 2375);
DISPLAY INVISIBLE (-4125 2375);
FORCEADD GND..1
R 2
(-4950 1650);
FORCEPROP 3 LASTPIN (-4950 1700) SIG_NAME GND\g
J 0
(-4940 1710);
DISPLAY 0.659574 (-4940 1710);
PAINT MONO (-4940 1710);
DISPLAY INVISIBLE (-4940 1710);
FORCEPROP 1 LAST VOLTAGE 0
J 0
(-4950 1650);
PAINT SKYBLUE (-4950 1650);
DISPLAY INVISIBLE (-4950 1650);
FORCEPROP 2 LAST BOM_COST MEM
J 0
(-4950 1655);
PAINT ORANGE (-4950 1655);
DISPLAY INVISIBLE (-4950 1655);
FORCEPROP 2 LAST CDS_LIB mstr_symbols
J 0
(-4950 1650);
DISPLAY 0.787234 (-4950 1650);
PAINT MONO (-4950 1650);
DISPLAY INVISIBLE (-4950 1650);
FORCEPROP 1 LAST SIZE 1B
J 2
(-5025 1600);
DISPLAY 1.170213 (-5025 1600);
PAINT GREEN (-5025 1600);
DISPLAY INVISIBLE (-5025 1600);
FORCEPROP 1 LAST BODY_TYPE PLUMBING
J 2
(-4905 1607);
DISPLAY 0.340426 (-4905 1607);
PAINT GREEN (-4905 1607);
DISPLAY INVISIBLE (-4905 1607);
FORCEPROP 1 LAST PATH I184
J 2
(-5025 1650);
DISPLAY 1.404255 (-5025 1650);
PAINT GREEN (-5025 1650);
DISPLAY INVISIBLE (-5025 1650);
FORCEPROP 2 LAST ROOM DDR4_CH_A
J 0
(-4950 1655);
PAINT ORANGE (-4950 1655);
DISPLAY INVISIBLE (-4950 1655);
FORCEPROP 1 LAST HDL_POWER GND
J 2
(-4950 1800);
DISPLAY 0.553191 (-4950 1800);
PAINT GREEN (-4950 1800);
DISPLAY INVISIBLE (-4950 1800);
FORCEADD OFFPAGE..1
(-3800 1600);
FORCEPROP 2 LAST $XR0 99 
J 0
(-4051 1600);
DISPLAY 0.638298 (-4051 1600);
PAINT MONO (-4051 1600);
FORCEPROP 2 LAST $XR1 43 
J 0
(-4141 1600);
DISPLAY 0.638298 (-4141 1600);
PAINT MONO (-4141 1600);
FORCEPROP 2 LAST $XR2 44 
J 0
(-4231 1600);
DISPLAY 0.638298 (-4231 1600);
PAINT MONO (-4231 1600);
FORCEPROP 2 LAST $XR3 45 
J 0
(-4321 1600);
DISPLAY 0.638298 (-4321 1600);
PAINT MONO (-4321 1600);
FORCEPROP 2 LAST $XR4 46 
J 0
(-4411 1600);
DISPLAY 0.638298 (-4411 1600);
PAINT MONO (-4411 1600);
FORCEPROP 2 LAST $XR5 48 
J 0
(-4501 1600);
DISPLAY 0.638298 (-4501 1600);
PAINT MONO (-4501 1600);
FORCEPROP 2 LAST CDS_LIB mstr_standard
J 0
(-3800 1600);
DISPLAY 0.787234 (-3800 1600);
PAINT MONO (-3800 1600);
DISPLAY INVISIBLE (-3800 1600);
FORCEPROP 1 LAST OFFPAGE TRUE
J 0
(-3475 1475);
DISPLAY 0.936170 (-3475 1475);
PAINT GREEN (-3475 1475);
DISPLAY INVISIBLE (-3475 1475);
FORCEPROP 1 LAST COMMENT_BODY TRUE
J 0
(-3675 1500);
DISPLAY 0.936170 (-3675 1500);
PAINT GREEN (-3675 1500);
DISPLAY INVISIBLE (-3675 1500);
FORCEPROP 2 LAST PATH I186
J 0
(-4075 1650);
DISPLAY 0.787234 (-4075 1650);
PAINT ORANGE (-4075 1650);
DISPLAY INVISIBLE (-4075 1650);
FORCEADD OFFPAGE..6
(-3800 1650);
FORCEPROP 2 LAST $XR0 43 
J 0
(-4049 1650);
DISPLAY 0.638298 (-4049 1650);
PAINT MONO (-4049 1650);
FORCEPROP 2 LAST $XR1 44 
J 0
(-4139 1650);
DISPLAY 0.638298 (-4139 1650);
PAINT MONO (-4139 1650);
FORCEPROP 2 LAST $XR2 45 
J 0
(-4229 1650);
DISPLAY 0.638298 (-4229 1650);
PAINT MONO (-4229 1650);
FORCEPROP 2 LAST $XR3 46 
J 0
(-4319 1650);
DISPLAY 0.638298 (-4319 1650);
PAINT MONO (-4319 1650);
FORCEPROP 2 LAST $XR4 48 
J 0
(-4409 1650);
DISPLAY 0.638298 (-4409 1650);
PAINT MONO (-4409 1650);
FORCEPROP 2 LAST $XR5 99 
J 0
(-4499 1650);
DISPLAY 0.638298 (-4499 1650);
PAINT MONO (-4499 1650);
FORCEPROP 2 LASTPIN (-3750 1650) SIG_NAME SMB_DDR_ABC_VPP_SDA
J 0
(-3710 1660);
DISPLAY 0.617021 (-3710 1660);
PAINT ORANGE (-3710 1660);
FORCEPROP 2 LAST CDS_LIB mstr_standard
J 0
(-3800 1650);
DISPLAY 0.787234 (-3800 1650);
PAINT MONO (-3800 1650);
DISPLAY INVISIBLE (-3800 1650);
FORCEPROP 1 LAST OFFPAGE TRUE
J 0
(-3475 1525);
DISPLAY 0.936170 (-3475 1525);
PAINT GREEN (-3475 1525);
DISPLAY INVISIBLE (-3475 1525);
FORCEPROP 1 LAST COMMENT_BODY TRUE
J 0
(-3700 1575);
DISPLAY 0.936170 (-3700 1575);
PAINT GREEN (-3700 1575);
DISPLAY INVISIBLE (-3700 1575);
FORCEPROP 2 LAST PATH I187
J 0
(-4100 1700);
DISPLAY 0.787234 (-4100 1700);
PAINT ORANGE (-4100 1700);
DISPLAY INVISIBLE (-4100 1700);
FORCEADD CAP_A..1
R 2
(-4650 1300);
FORCEPROP 1 LAST LOCATION C4G19
J 2
(-4700 1400);
DISPLAY 0.617021 (-4700 1400);
PAINT AQUA (-4700 1400);
FORCEPROP 1 LAST PART_NUMBER A36096-045
J 2
(-4700 1150);
DISPLAY 0.617021 (-4700 1150);
PAINT BLUE (-4700 1150);
FORCEPROP 1 LAST VALUE 0.01UF
J 2
(-4700 1350);
DISPLAY 0.617021 (-4700 1350);
PAINT SKYBLUE (-4700 1350);
FORCEPROP 1 LAST TOLERANCE 10%
J 2
(-4700 1250);
DISPLAY 0.617021 (-4700 1250);
PAINT SKYBLUE (-4700 1250);
FORCEPROP 1 LAST PACK_TYPE 0402V
J 2
(-4700 1100);
DISPLAY 0.617021 (-4700 1100);
PAINT SKYBLUE (-4700 1100);
FORCEPROP 1 LAST VOLTAGE 25V
J 2
(-4700 1300);
DISPLAY 0.617021 (-4700 1300);
PAINT SKYBLUE (-4700 1300);
FORCEPROP 1 LAST MATERIAL X7R
J 2
(-4700 1200);
DISPLAY 0.617021 (-4700 1200);
PAINT SKYBLUE (-4700 1200);
FORCEPROP 1 LASTPIN (-4650 1400) $PN 1
J 2
(-4660 1380);
DISPLAY 0.617021 (-4660 1380);
PAINT ORANGE (-4660 1380);
FORCEPROP 1 LASTPIN (-4650 1200) $PN 2
J 2
(-4660 1180);
DISPLAY 0.617021 (-4660 1180);
PAINT ORANGE (-4660 1180);
FORCEPROP 2 LAST CDS_LOCATION C4G19
J 2
(-4700 1400);
DISPLAY 0.617021 (-4700 1400);
PAINT AQUA (-4700 1400);
DISPLAY INVISIBLE (-4700 1400);
FORCEPROP 2 LAST BOM_COST MEM
J 0
(-4650 1300);
PAINT ORANGE (-4650 1300);
DISPLAY INVISIBLE (-4650 1300);
FORCEPROP 2 LAST CDS_LIB dev_discrete
J 0
(-4650 1300);
PAINT ORANGE (-4650 1300);
DISPLAY INVISIBLE (-4650 1300);
FORCEPROP 2 LAST CDS_SEC 1
J 0
(-4700 1450);
PAINT ORANGE (-4700 1450);
DISPLAY INVISIBLE (-4700 1450);
FORCEPROP 2 LAST SEC_TYPE 0402V
J 0
(-4700 1500);
DISPLAY 1.021277 (-4700 1500);
PAINT ORANGE (-4700 1500);
DISPLAY INVISIBLE (-4700 1500);
FORCEPROP 2 LAST SEC 1
J 0
(-4700 1500);
PAINT MONO (-4700 1500);
DISPLAY INVISIBLE (-4700 1500);
FORCEPROP 1 LAST PATH I188
J 2
(-4700 1450);
DISPLAY 0.978723 (-4700 1450);
PAINT WHITE (-4700 1450);
DISPLAY INVISIBLE (-4700 1450);
FORCEPROP 2 LAST ROOM DDR4_CH_C
J 0
(-4650 1300);
PAINT ORANGE (-4650 1300);
DISPLAY INVISIBLE (-4650 1300);
FORCEADD GND..1
(-4650 1050);
FORCEPROP 3 LASTPIN (-4650 1100) SIG_NAME GND\g
J 0
(-4640 1110);
DISPLAY 0.659574 (-4640 1110);
PAINT MONO (-4640 1110);
DISPLAY INVISIBLE (-4640 1110);
FORCEPROP 1 LAST VOLTAGE 0
J 0
(-4650 1050);
PAINT SKYBLUE (-4650 1050);
DISPLAY INVISIBLE (-4650 1050);
FORCEPROP 2 LAST BOM_COST MEM
J 0
(-4650 1055);
PAINT ORANGE (-4650 1055);
DISPLAY INVISIBLE (-4650 1055);
FORCEPROP 2 LAST CDS_LIB mstr_symbols
J 0
(-4650 1050);
PAINT ORANGE (-4650 1050);
DISPLAY INVISIBLE (-4650 1050);
FORCEPROP 1 LAST SIZE 1B
J 0
(-4575 1000);
DISPLAY 1.787234 (-4575 1000);
PAINT GREEN (-4575 1000);
DISPLAY INVISIBLE (-4575 1000);
FORCEPROP 1 LAST BODY_TYPE PLUMBING
J 0
(-4695 1007);
DISPLAY 0.340426 (-4695 1007);
PAINT GREEN (-4695 1007);
DISPLAY INVISIBLE (-4695 1007);
FORCEPROP 1 LAST PATH I189
J 0
(-4575 1050);
DISPLAY 1.404255 (-4575 1050);
PAINT GREEN (-4575 1050);
DISPLAY INVISIBLE (-4575 1050);
FORCEPROP 2 LAST ROOM DDR4_CH_A
J 0
(-4650 1055);
PAINT ORANGE (-4650 1055);
DISPLAY INVISIBLE (-4650 1055);
FORCEPROP 1 LAST HDL_POWER GND
J 0
(-4650 1200);
DISPLAY 1.404255 (-4650 1200);
PAINT GREEN (-4650 1200);
DISPLAY INVISIBLE (-4650 1200);
FORCEADD TAP..6
R 2
(900 4450);
FORCEPROP 3 LASTPIN (850 4450) SIG_NAME M_C_DQS_DN<10>
J 0
(860 4460);
DISPLAY 0.659574 (860 4460);
PAINT MONO (860 4460);
DISPLAY INVISIBLE (860 4460);
FORCEPROP 1 LASTPIN (850 4450) BN 10
J 2
(900 4460);
DISPLAY 0.617021 (900 4460);
PAINT PINK (900 4460);
FORCEPROP 2 LAST CDS_LIB mstr_standard
J 0
(900 4450);
DISPLAY 0.787234 (900 4450);
PAINT MONO (900 4450);
DISPLAY INVISIBLE (900 4450);
FORCEPROP 1 LAST BODY_TYPE PLUMBING
J 2
(900 4400);
DISPLAY 1.234043 (900 4400);
PAINT GREEN (900 4400);
DISPLAY INVISIBLE (900 4400);
FORCEPROP 1 LAST HDL_TAP TRUE
J 2
(575 4325);
DISPLAY 1.234043 (575 4325);
PAINT GREEN (575 4325);
DISPLAY INVISIBLE (575 4325);
FORCEPROP 1 LAST PATH I19
J 2
(900 4450);
DISPLAY 0.936170 (900 4450);
PAINT GREEN (900 4450);
DISPLAY INVISIBLE (900 4450);
FORCEADD PVPP_ABC..1
(-700 3050);
FORCEPROP 3 LASTPIN (-700 3000) SIG_NAME PVPP_ABC\g
J 0
(-690 3010);
DISPLAY 0.659574 (-690 3010);
PAINT MONO (-690 3010);
DISPLAY INVISIBLE (-690 3010);
FORCEPROP 1 LAST VOLTAGE 2.5V
J 0
(-745 3007);
DISPLAY 0.340426 (-745 3007);
PAINT SKYBLUE (-745 3007);
DISPLAY INVISIBLE (-745 3007);
FORCEPROP 0 LAST BOM_COST MEM
J 0
(-700 3150);
PAINT ORANGE (-700 3150);
DISPLAY INVISIBLE (-700 3150);
FORCEPROP 2 LAST CDS_LIB mstr_symbols
J 0
(-700 3050);
PAINT ORANGE (-700 3050);
DISPLAY INVISIBLE (-700 3050);
FORCEPROP 1 LAST BODY_TYPE PLUMBING
J 0
(-745 3007);
DISPLAY 0.340426 (-745 3007);
PAINT GREEN (-745 3007);
DISPLAY INVISIBLE (-745 3007);
FORCEPROP 1 LAST PATH I190
J 0
(-650 3075);
DISPLAY 0.872340 (-650 3075);
PAINT AQUA (-650 3075);
DISPLAY INVISIBLE (-650 3075);
FORCEPROP 2 LAST ROOM DDR4_CH_A
J 0
(-700 3150);
PAINT ORANGE (-700 3150);
DISPLAY INVISIBLE (-700 3150);
FORCEPROP 1 LAST HDL_POWER PVPP_ABC
J 1
(-700 3100);
DISPLAY 0.872340 (-700 3100);
PAINT GREEN (-700 3100);
DISPLAY INVISIBLE (-700 3100);
FORCEADD PVPP_ABC..1
(-4950 2000);
FORCEPROP 3 LASTPIN (-4950 1950) SIG_NAME PVPP_ABC\g
J 0
(-4940 1960);
DISPLAY 0.659574 (-4940 1960);
PAINT MONO (-4940 1960);
DISPLAY INVISIBLE (-4940 1960);
FORCEPROP 1 LAST VOLTAGE 2.5V
J 0
(-4995 1957);
DISPLAY 0.340426 (-4995 1957);
PAINT SKYBLUE (-4995 1957);
DISPLAY INVISIBLE (-4995 1957);
FORCEPROP 0 LAST BOM_COST MEM
J 0
(-4950 2100);
PAINT ORANGE (-4950 2100);
DISPLAY INVISIBLE (-4950 2100);
FORCEPROP 2 LAST CDS_LIB mstr_symbols
J 0
(-4950 2000);
PAINT ORANGE (-4950 2000);
DISPLAY INVISIBLE (-4950 2000);
FORCEPROP 1 LAST BODY_TYPE PLUMBING
J 0
(-4995 1957);
DISPLAY 0.340426 (-4995 1957);
PAINT GREEN (-4995 1957);
DISPLAY INVISIBLE (-4995 1957);
FORCEPROP 1 LAST PATH I191
J 0
(-4900 2025);
DISPLAY 0.872340 (-4900 2025);
PAINT AQUA (-4900 2025);
DISPLAY INVISIBLE (-4900 2025);
FORCEPROP 2 LAST ROOM DDR4_CH_A
J 0
(-4950 2100);
PAINT ORANGE (-4950 2100);
DISPLAY INVISIBLE (-4950 2100);
FORCEPROP 1 LAST HDL_POWER PVPP_ABC
J 1
(-4950 2050);
DISPLAY 0.872340 (-4950 2050);
PAINT GREEN (-4950 2050);
DISPLAY INVISIBLE (-4950 2050);
FORCEADD OFFPAGE..1
(-3850 1200);
FORCEPROP 2 LAST $XR0 89 
J 0
(-4101 1200);
DISPLAY 0.638298 (-4101 1200);
PAINT MONO (-4101 1200);
FORCEPROP 2 LAST $XR1 43 
J 0
(-4191 1200);
DISPLAY 0.638298 (-4191 1200);
PAINT MONO (-4191 1200);
FORCEPROP 2 LAST $XR2 44 
J 0
(-4281 1200);
DISPLAY 0.638298 (-4281 1200);
PAINT MONO (-4281 1200);
FORCEPROP 2 LAST $XR3 45 
J 0
(-4371 1200);
DISPLAY 0.638298 (-4371 1200);
PAINT MONO (-4371 1200);
FORCEPROP 2 LAST $XR4 46 
J 0
(-4461 1200);
DISPLAY 0.638298 (-4461 1200);
PAINT MONO (-4461 1200);
FORCEPROP 2 LAST $XR5 48 
J 0
(-4551 1200);
DISPLAY 0.638298 (-4551 1200);
PAINT MONO (-4551 1200);
FORCEPROP 2 LAST CDS_LIB mstr_standard
J 0
(-3850 1200);
PAINT ORANGE (-3850 1200);
DISPLAY INVISIBLE (-3850 1200);
FORCEPROP 1 LAST OFFPAGE TRUE
J 0
(-3525 1075);
DISPLAY 0.936170 (-3525 1075);
PAINT GREEN (-3525 1075);
DISPLAY INVISIBLE (-3525 1075);
FORCEPROP 1 LAST COMMENT_BODY TRUE
J 0
(-3725 1100);
DISPLAY 0.936170 (-3725 1100);
PAINT GREEN (-3725 1100);
DISPLAY INVISIBLE (-3725 1100);
FORCEPROP 2 LAST PATH I192
J 0
(-3800 1275);
PAINT ORANGE (-3800 1275);
DISPLAY INVISIBLE (-3800 1275);
FORCEADD TAP..6
(-3600 3450);
FORCEPROP 3 LASTPIN (-3550 3450) SIG_NAME M_C_CLK_DP<1>
J 0
(-3540 3460);
DISPLAY 0.659574 (-3540 3460);
PAINT MONO (-3540 3460);
DISPLAY INVISIBLE (-3540 3460);
FORCEPROP 1 LASTPIN (-3550 3450) BN 1
J 0
(-3602 3458);
DISPLAY 0.617021 (-3602 3458);
PAINT PINK (-3602 3458);
FORCEPROP 2 LAST CDS_LIB mstr_standard
J 0
(-3600 3450);
PAINT MONO (-3600 3450);
DISPLAY INVISIBLE (-3600 3450);
FORCEPROP 1 LAST BODY_TYPE PLUMBING
J 0
(-3600 3400);
DISPLAY 1.234043 (-3600 3400);
PAINT GREEN (-3600 3400);
DISPLAY INVISIBLE (-3600 3400);
FORCEPROP 1 LAST HDL_TAP TRUE
J 0
(-3275 3325);
DISPLAY 1.234043 (-3275 3325);
PAINT GREEN (-3275 3325);
DISPLAY INVISIBLE (-3275 3325);
FORCEPROP 1 LAST PATH I196
J 0
(-3602 3450);
DISPLAY 0.872340 (-3602 3450);
PAINT GREEN (-3602 3450);
DISPLAY INVISIBLE (-3602 3450);
FORCEADD TAP..6
(-3750 3400);
FORCEPROP 3 LASTPIN (-3700 3400) SIG_NAME M_C_CLK_DN<1>
J 0
(-3690 3410);
DISPLAY 0.659574 (-3690 3410);
PAINT MONO (-3690 3410);
DISPLAY INVISIBLE (-3690 3410);
FORCEPROP 1 LASTPIN (-3700 3400) BN 1
J 0
(-3752 3408);
DISPLAY 0.617021 (-3752 3408);
PAINT PINK (-3752 3408);
FORCEPROP 2 LAST CDS_LIB mstr_standard
J 0
(-3750 3400);
PAINT MONO (-3750 3400);
DISPLAY INVISIBLE (-3750 3400);
FORCEPROP 1 LAST BODY_TYPE PLUMBING
J 0
(-3750 3350);
DISPLAY 1.234043 (-3750 3350);
PAINT GREEN (-3750 3350);
DISPLAY INVISIBLE (-3750 3350);
FORCEPROP 1 LAST HDL_TAP TRUE
J 0
(-3425 3275);
DISPLAY 1.234043 (-3425 3275);
PAINT GREEN (-3425 3275);
DISPLAY INVISIBLE (-3425 3275);
FORCEPROP 1 LAST PATH I197
J 0
(-3752 3400);
DISPLAY 0.872340 (-3752 3400);
PAINT GREEN (-3752 3400);
DISPLAY INVISIBLE (-3752 3400);
FORCEADD P12V_NVDIMM_ABC..1
(700 3125);
FORCEPROP 3 LASTPIN (700 3075) SIG_NAME P12V_NVDIMM_ABC\g
J 0
(710 3085);
DISPLAY 0.659574 (710 3085);
PAINT MONO (710 3085);
DISPLAY INVISIBLE (710 3085);
FORCEPROP 1 LAST VOLTAGE 12.0
J 0
(655 3082);
DISPLAY 0.340426 (655 3082);
PAINT SKYBLUE (655 3082);
DISPLAY INVISIBLE (655 3082);
FORCEPROP 2 LAST CDS_LIB mstr_symbols
J 0
(700 3125);
PAINT ORANGE (700 3125);
DISPLAY INVISIBLE (700 3125);
FORCEPROP 1 LAST BODY_TYPE PLUMBING
J 0
(655 3082);
DISPLAY 0.340426 (655 3082);
PAINT GREEN (655 3082);
DISPLAY INVISIBLE (655 3082);
FORCEPROP 1 LAST PATH I198
J 0
(750 3150);
DISPLAY 0.872340 (750 3150);
PAINT AQUA (750 3150);
DISPLAY INVISIBLE (750 3150);
FORCEPROP 1 LAST HDL_POWER P12V_NVDIMM_ABC
J 1
(700 3150);
DISPLAY 0.872340 (700 3150);
PAINT GREEN (700 3150);
DISPLAY INVISIBLE (700 3150);
FORCEADD OFFPAGE..3
(1600 5200);
FORCEPROP 2 LAST $XR0 25 
J 0
(1814 5200);
DISPLAY 0.638298 (1814 5200);
PAINT MONO (1814 5200);
FORCEPROP 2 LAST $XR1 48 
J 0
(1904 5200);
DISPLAY 0.638298 (1904 5200);
PAINT MONO (1904 5200);
FORCEPROP 2 LAST CDS_LIB mstr_standard
J 0
(1600 5200);
DISPLAY 0.787234 (1600 5200);
PAINT MONO (1600 5200);
DISPLAY INVISIBLE (1600 5200);
FORCEPROP 1 LAST OFFPAGE TRUE
J 0
(1925 5075);
DISPLAY 0.936170 (1925 5075);
PAINT GREEN (1925 5075);
DISPLAY INVISIBLE (1925 5075);
FORCEPROP 1 LAST COMMENT_BODY TRUE
J 0
(1550 5100);
DISPLAY 0.936170 (1550 5100);
PAINT GREEN (1550 5100);
DISPLAY INVISIBLE (1550 5100);
FORCEPROP 2 LAST PATH I2
J 0
(1800 5275);
DISPLAY 0.787234 (1800 5275);
PAINT MONO (1800 5275);
DISPLAY INVISIBLE (1800 5275);
FORCEADD TAP..6
R 2
(900 4550);
FORCEPROP 3 LASTPIN (850 4550) SIG_NAME M_C_DQS_DN<11>
J 0
(860 4560);
DISPLAY 0.659574 (860 4560);
PAINT MONO (860 4560);
DISPLAY INVISIBLE (860 4560);
FORCEPROP 1 LASTPIN (850 4550) BN 11
J 2
(900 4560);
DISPLAY 0.617021 (900 4560);
PAINT PINK (900 4560);
FORCEPROP 2 LAST CDS_LIB mstr_standard
J 0
(900 4550);
DISPLAY 0.787234 (900 4550);
PAINT MONO (900 4550);
DISPLAY INVISIBLE (900 4550);
FORCEPROP 1 LAST BODY_TYPE PLUMBING
J 2
(900 4500);
DISPLAY 1.234043 (900 4500);
PAINT GREEN (900 4500);
DISPLAY INVISIBLE (900 4500);
FORCEPROP 1 LAST HDL_TAP TRUE
J 2
(575 4425);
DISPLAY 1.234043 (575 4425);
PAINT GREEN (575 4425);
DISPLAY INVISIBLE (575 4425);
FORCEPROP 1 LAST PATH I20
J 2
(900 4550);
DISPLAY 0.936170 (900 4550);
PAINT GREEN (900 4550);
DISPLAY INVISIBLE (900 4550);
FORCEADD TAP..6
R 2
(900 4350);
FORCEPROP 3 LASTPIN (850 4350) SIG_NAME M_C_DQS_DN<9>
J 0
(860 4360);
DISPLAY 0.659574 (860 4360);
PAINT MONO (860 4360);
DISPLAY INVISIBLE (860 4360);
FORCEPROP 1 LASTPIN (850 4350) BN 9
J 2
(900 4360);
DISPLAY 0.617021 (900 4360);
PAINT PINK (900 4360);
FORCEPROP 2 LAST CDS_LIB mstr_standard
J 0
(900 4350);
DISPLAY 0.787234 (900 4350);
PAINT MONO (900 4350);
DISPLAY INVISIBLE (900 4350);
FORCEPROP 1 LAST BODY_TYPE PLUMBING
J 2
(900 4300);
DISPLAY 1.234043 (900 4300);
PAINT GREEN (900 4300);
DISPLAY INVISIBLE (900 4300);
FORCEPROP 1 LAST HDL_TAP TRUE
J 2
(575 4225);
DISPLAY 1.234043 (575 4225);
PAINT GREEN (575 4225);
DISPLAY INVISIBLE (575 4225);
FORCEPROP 1 LAST PATH I21
J 2
(900 4350);
DISPLAY 0.936170 (900 4350);
PAINT GREEN (900 4350);
DISPLAY INVISIBLE (900 4350);
FORCEADD TAP..6
R 2
(700 4500);
FORCEPROP 3 LASTPIN (650 4500) SIG_NAME M_C_DQS_DP<10>
J 0
(660 4510);
DISPLAY 0.659574 (660 4510);
PAINT MONO (660 4510);
DISPLAY INVISIBLE (660 4510);
FORCEPROP 1 LASTPIN (650 4500) BN 10
J 2
(700 4510);
DISPLAY 0.617021 (700 4510);
PAINT PINK (700 4510);
FORCEPROP 2 LAST CDS_LIB mstr_standard
J 0
(700 4500);
DISPLAY 0.787234 (700 4500);
PAINT MONO (700 4500);
DISPLAY INVISIBLE (700 4500);
FORCEPROP 1 LAST BODY_TYPE PLUMBING
J 2
(700 4450);
DISPLAY 1.234043 (700 4450);
PAINT GREEN (700 4450);
DISPLAY INVISIBLE (700 4450);
FORCEPROP 1 LAST HDL_TAP TRUE
J 2
(375 4375);
DISPLAY 1.234043 (375 4375);
PAINT GREEN (375 4375);
DISPLAY INVISIBLE (375 4375);
FORCEPROP 1 LAST PATH I22
J 2
(700 4500);
DISPLAY 0.936170 (700 4500);
PAINT GREEN (700 4500);
DISPLAY INVISIBLE (700 4500);
FORCEADD TAP..6
R 2
(700 4400);
FORCEPROP 3 LASTPIN (650 4400) SIG_NAME M_C_DQS_DP<9>
J 0
(660 4410);
DISPLAY 0.659574 (660 4410);
PAINT MONO (660 4410);
DISPLAY INVISIBLE (660 4410);
FORCEPROP 1 LASTPIN (650 4400) BN 9
J 2
(700 4410);
DISPLAY 0.617021 (700 4410);
PAINT PINK (700 4410);
FORCEPROP 2 LAST CDS_LIB mstr_standard
J 0
(700 4400);
DISPLAY 0.787234 (700 4400);
PAINT MONO (700 4400);
DISPLAY INVISIBLE (700 4400);
FORCEPROP 1 LAST BODY_TYPE PLUMBING
J 2
(700 4350);
DISPLAY 1.234043 (700 4350);
PAINT GREEN (700 4350);
DISPLAY INVISIBLE (700 4350);
FORCEPROP 1 LAST HDL_TAP TRUE
J 2
(375 4275);
DISPLAY 1.234043 (375 4275);
PAINT GREEN (375 4275);
DISPLAY INVISIBLE (375 4275);
FORCEPROP 1 LAST PATH I23
J 2
(700 4400);
DISPLAY 0.936170 (700 4400);
PAINT GREEN (700 4400);
DISPLAY INVISIBLE (700 4400);
FORCEADD TAP..6
R 2
(900 4150);
FORCEPROP 3 LASTPIN (850 4150) SIG_NAME M_C_DQS_DN<7>
J 0
(860 4160);
DISPLAY 0.659574 (860 4160);
PAINT MONO (860 4160);
DISPLAY INVISIBLE (860 4160);
FORCEPROP 1 LASTPIN (850 4150) BN 7
J 2
(900 4160);
DISPLAY 0.617021 (900 4160);
PAINT PINK (900 4160);
FORCEPROP 2 LAST CDS_LIB mstr_standard
J 0
(900 4150);
DISPLAY 0.787234 (900 4150);
PAINT MONO (900 4150);
DISPLAY INVISIBLE (900 4150);
FORCEPROP 1 LAST BODY_TYPE PLUMBING
J 2
(900 4100);
DISPLAY 1.234043 (900 4100);
PAINT GREEN (900 4100);
DISPLAY INVISIBLE (900 4100);
FORCEPROP 1 LAST HDL_TAP TRUE
J 2
(575 4025);
DISPLAY 1.234043 (575 4025);
PAINT GREEN (575 4025);
DISPLAY INVISIBLE (575 4025);
FORCEPROP 1 LAST PATH I24
J 2
(900 4150);
DISPLAY 0.936170 (900 4150);
PAINT GREEN (900 4150);
DISPLAY INVISIBLE (900 4150);
FORCEADD TAP..6
R 2
(900 4250);
FORCEPROP 3 LASTPIN (850 4250) SIG_NAME M_C_DQS_DN<8>
J 0
(860 4260);
DISPLAY 0.659574 (860 4260);
PAINT MONO (860 4260);
DISPLAY INVISIBLE (860 4260);
FORCEPROP 1 LASTPIN (850 4250) BN 8
J 2
(900 4260);
DISPLAY 0.617021 (900 4260);
PAINT PINK (900 4260);
FORCEPROP 2 LAST CDS_LIB mstr_standard
J 0
(900 4250);
DISPLAY 0.787234 (900 4250);
PAINT MONO (900 4250);
DISPLAY INVISIBLE (900 4250);
FORCEPROP 1 LAST BODY_TYPE PLUMBING
J 2
(900 4200);
DISPLAY 1.234043 (900 4200);
PAINT GREEN (900 4200);
DISPLAY INVISIBLE (900 4200);
FORCEPROP 1 LAST HDL_TAP TRUE
J 2
(575 4125);
DISPLAY 1.234043 (575 4125);
PAINT GREEN (575 4125);
DISPLAY INVISIBLE (575 4125);
FORCEPROP 1 LAST PATH I25
J 2
(900 4250);
DISPLAY 0.936170 (900 4250);
PAINT GREEN (900 4250);
DISPLAY INVISIBLE (900 4250);
FORCEADD TAP..6
R 2
(700 4300);
FORCEPROP 3 LASTPIN (650 4300) SIG_NAME M_C_DQS_DP<8>
J 0
(660 4310);
DISPLAY 0.659574 (660 4310);
PAINT MONO (660 4310);
DISPLAY INVISIBLE (660 4310);
FORCEPROP 1 LASTPIN (650 4300) BN 8
J 2
(700 4310);
DISPLAY 0.617021 (700 4310);
PAINT PINK (700 4310);
FORCEPROP 2 LAST CDS_LIB mstr_standard
J 0
(700 4300);
DISPLAY 0.787234 (700 4300);
PAINT MONO (700 4300);
DISPLAY INVISIBLE (700 4300);
FORCEPROP 1 LAST BODY_TYPE PLUMBING
J 2
(700 4250);
DISPLAY 1.234043 (700 4250);
PAINT GREEN (700 4250);
DISPLAY INVISIBLE (700 4250);
FORCEPROP 1 LAST HDL_TAP TRUE
J 2
(375 4175);
DISPLAY 1.234043 (375 4175);
PAINT GREEN (375 4175);
DISPLAY INVISIBLE (375 4175);
FORCEPROP 1 LAST PATH I26
J 2
(700 4300);
DISPLAY 0.936170 (700 4300);
PAINT GREEN (700 4300);
DISPLAY INVISIBLE (700 4300);
FORCEADD TAP..6
R 2
(700 4200);
FORCEPROP 3 LASTPIN (650 4200) SIG_NAME M_C_DQS_DP<7>
J 0
(660 4210);
DISPLAY 0.659574 (660 4210);
PAINT MONO (660 4210);
DISPLAY INVISIBLE (660 4210);
FORCEPROP 1 LASTPIN (650 4200) BN 7
J 2
(700 4210);
DISPLAY 0.617021 (700 4210);
PAINT PINK (700 4210);
FORCEPROP 2 LAST CDS_LIB mstr_standard
J 0
(700 4200);
DISPLAY 0.787234 (700 4200);
PAINT MONO (700 4200);
DISPLAY INVISIBLE (700 4200);
FORCEPROP 1 LAST BODY_TYPE PLUMBING
J 2
(700 4150);
DISPLAY 1.234043 (700 4150);
PAINT GREEN (700 4150);
DISPLAY INVISIBLE (700 4150);
FORCEPROP 1 LAST HDL_TAP TRUE
J 2
(375 4075);
DISPLAY 1.234043 (375 4075);
PAINT GREEN (375 4075);
DISPLAY INVISIBLE (375 4075);
FORCEPROP 1 LAST PATH I27
J 2
(700 4200);
DISPLAY 0.936170 (700 4200);
PAINT GREEN (700 4200);
DISPLAY INVISIBLE (700 4200);
FORCEADD TAP..6
R 2
(700 4100);
FORCEPROP 3 LASTPIN (650 4100) SIG_NAME M_C_DQS_DP<6>
J 0
(660 4110);
DISPLAY 0.659574 (660 4110);
PAINT MONO (660 4110);
DISPLAY INVISIBLE (660 4110);
FORCEPROP 1 LASTPIN (650 4100) BN 6
J 2
(700 4110);
DISPLAY 0.617021 (700 4110);
PAINT PINK (700 4110);
FORCEPROP 2 LAST CDS_LIB mstr_standard
J 0
(700 4100);
DISPLAY 0.787234 (700 4100);
PAINT MONO (700 4100);
DISPLAY INVISIBLE (700 4100);
FORCEPROP 1 LAST BODY_TYPE PLUMBING
J 2
(700 4050);
DISPLAY 1.234043 (700 4050);
PAINT GREEN (700 4050);
DISPLAY INVISIBLE (700 4050);
FORCEPROP 1 LAST HDL_TAP TRUE
J 2
(375 3975);
DISPLAY 1.234043 (375 3975);
PAINT GREEN (375 3975);
DISPLAY INVISIBLE (375 3975);
FORCEPROP 1 LAST PATH I28
J 2
(700 4100);
DISPLAY 0.936170 (700 4100);
PAINT GREEN (700 4100);
DISPLAY INVISIBLE (700 4100);
FORCEADD TAP..6
R 2
(900 3950);
FORCEPROP 3 LASTPIN (850 3950) SIG_NAME M_C_DQS_DN<5>
J 0
(860 3960);
DISPLAY 0.659574 (860 3960);
PAINT MONO (860 3960);
DISPLAY INVISIBLE (860 3960);
FORCEPROP 1 LASTPIN (850 3950) BN 5
J 2
(900 3960);
DISPLAY 0.617021 (900 3960);
PAINT PINK (900 3960);
FORCEPROP 2 LAST CDS_LIB mstr_standard
J 0
(900 3950);
DISPLAY 0.787234 (900 3950);
PAINT MONO (900 3950);
DISPLAY INVISIBLE (900 3950);
FORCEPROP 1 LAST BODY_TYPE PLUMBING
J 2
(900 3900);
DISPLAY 1.234043 (900 3900);
PAINT GREEN (900 3900);
DISPLAY INVISIBLE (900 3900);
FORCEPROP 1 LAST HDL_TAP TRUE
J 2
(575 3825);
DISPLAY 1.234043 (575 3825);
PAINT GREEN (575 3825);
DISPLAY INVISIBLE (575 3825);
FORCEPROP 1 LAST PATH I29
J 2
(900 3950);
DISPLAY 0.936170 (900 3950);
PAINT GREEN (900 3950);
DISPLAY INVISIBLE (900 3950);
FORCEADD TAP..6
R 2
(900 5150);
FORCEPROP 3 LASTPIN (850 5150) SIG_NAME M_C_DQS_DN<17>
J 0
(860 5160);
DISPLAY 0.659574 (860 5160);
PAINT MONO (860 5160);
DISPLAY INVISIBLE (860 5160);
FORCEPROP 1 LASTPIN (850 5150) BN 17
J 2
(900 5160);
DISPLAY 0.617021 (900 5160);
PAINT PINK (900 5160);
FORCEPROP 2 LAST CDS_LIB mstr_standard
J 2
(900 5150);
DISPLAY 0.787234 (900 5150);
PAINT MONO (900 5150);
DISPLAY INVISIBLE (900 5150);
FORCEPROP 1 LAST BODY_TYPE PLUMBING
J 2
(900 5100);
DISPLAY 1.234043 (900 5100);
PAINT GREEN (900 5100);
DISPLAY INVISIBLE (900 5100);
FORCEPROP 1 LAST HDL_TAP TRUE
J 2
(575 5025);
DISPLAY 1.234043 (575 5025);
PAINT GREEN (575 5025);
DISPLAY INVISIBLE (575 5025);
FORCEPROP 1 LAST PATH I3
J 2
(900 5150);
DISPLAY 0.936170 (900 5150);
PAINT GREEN (900 5150);
DISPLAY INVISIBLE (900 5150);
FORCEADD TAP..6
R 2
(900 4050);
FORCEPROP 3 LASTPIN (850 4050) SIG_NAME M_C_DQS_DN<6>
J 0
(860 4060);
DISPLAY 0.659574 (860 4060);
PAINT MONO (860 4060);
DISPLAY INVISIBLE (860 4060);
FORCEPROP 1 LASTPIN (850 4050) BN 6
J 2
(900 4060);
DISPLAY 0.617021 (900 4060);
PAINT PINK (900 4060);
FORCEPROP 2 LAST CDS_LIB mstr_standard
J 0
(900 4050);
DISPLAY 0.787234 (900 4050);
PAINT MONO (900 4050);
DISPLAY INVISIBLE (900 4050);
FORCEPROP 1 LAST BODY_TYPE PLUMBING
J 2
(900 4000);
DISPLAY 1.234043 (900 4000);
PAINT GREEN (900 4000);
DISPLAY INVISIBLE (900 4000);
FORCEPROP 1 LAST HDL_TAP TRUE
J 2
(575 3925);
DISPLAY 1.234043 (575 3925);
PAINT GREEN (575 3925);
DISPLAY INVISIBLE (575 3925);
FORCEPROP 1 LAST PATH I30
J 2
(900 4050);
DISPLAY 0.936170 (900 4050);
PAINT GREEN (900 4050);
DISPLAY INVISIBLE (900 4050);
FORCEADD TAP..6
R 2
(900 3850);
FORCEPROP 3 LASTPIN (850 3850) SIG_NAME M_C_DQS_DN<4>
J 0
(860 3860);
DISPLAY 0.659574 (860 3860);
PAINT MONO (860 3860);
DISPLAY INVISIBLE (860 3860);
FORCEPROP 1 LASTPIN (850 3850) BN 4
J 2
(900 3860);
DISPLAY 0.617021 (900 3860);
PAINT PINK (900 3860);
FORCEPROP 2 LAST CDS_LIB mstr_standard
J 0
(900 3850);
DISPLAY 0.787234 (900 3850);
PAINT MONO (900 3850);
DISPLAY INVISIBLE (900 3850);
FORCEPROP 1 LAST BODY_TYPE PLUMBING
J 2
(900 3800);
DISPLAY 1.234043 (900 3800);
PAINT GREEN (900 3800);
DISPLAY INVISIBLE (900 3800);
FORCEPROP 1 LAST HDL_TAP TRUE
J 2
(575 3725);
DISPLAY 1.234043 (575 3725);
PAINT GREEN (575 3725);
DISPLAY INVISIBLE (575 3725);
FORCEPROP 1 LAST PATH I31
J 2
(900 3850);
DISPLAY 0.936170 (900 3850);
PAINT GREEN (900 3850);
DISPLAY INVISIBLE (900 3850);
FORCEADD TAP..6
R 2
(700 4000);
FORCEPROP 3 LASTPIN (650 4000) SIG_NAME M_C_DQS_DP<5>
J 0
(660 4010);
DISPLAY 0.659574 (660 4010);
PAINT MONO (660 4010);
DISPLAY INVISIBLE (660 4010);
FORCEPROP 1 LASTPIN (650 4000) BN 5
J 2
(700 4010);
DISPLAY 0.617021 (700 4010);
PAINT PINK (700 4010);
FORCEPROP 2 LAST CDS_LIB mstr_standard
J 0
(700 4000);
DISPLAY 0.787234 (700 4000);
PAINT MONO (700 4000);
DISPLAY INVISIBLE (700 4000);
FORCEPROP 1 LAST BODY_TYPE PLUMBING
J 2
(700 3950);
DISPLAY 1.234043 (700 3950);
PAINT GREEN (700 3950);
DISPLAY INVISIBLE (700 3950);
FORCEPROP 1 LAST HDL_TAP TRUE
J 2
(375 3875);
DISPLAY 1.234043 (375 3875);
PAINT GREEN (375 3875);
DISPLAY INVISIBLE (375 3875);
FORCEPROP 1 LAST PATH I32
J 2
(700 4000);
DISPLAY 0.936170 (700 4000);
PAINT GREEN (700 4000);
DISPLAY INVISIBLE (700 4000);
FORCEADD TAP..6
R 2
(700 3900);
FORCEPROP 3 LASTPIN (650 3900) SIG_NAME M_C_DQS_DP<4>
J 0
(660 3910);
DISPLAY 0.659574 (660 3910);
PAINT MONO (660 3910);
DISPLAY INVISIBLE (660 3910);
FORCEPROP 1 LASTPIN (650 3900) BN 4
J 2
(700 3910);
DISPLAY 0.617021 (700 3910);
PAINT PINK (700 3910);
FORCEPROP 2 LAST CDS_LIB mstr_standard
J 0
(700 3900);
DISPLAY 0.787234 (700 3900);
PAINT MONO (700 3900);
DISPLAY INVISIBLE (700 3900);
FORCEPROP 1 LAST BODY_TYPE PLUMBING
J 2
(700 3850);
DISPLAY 1.234043 (700 3850);
PAINT GREEN (700 3850);
DISPLAY INVISIBLE (700 3850);
FORCEPROP 1 LAST HDL_TAP TRUE
J 2
(375 3775);
DISPLAY 1.234043 (375 3775);
PAINT GREEN (375 3775);
DISPLAY INVISIBLE (375 3775);
FORCEPROP 1 LAST PATH I33
J 2
(700 3900);
DISPLAY 0.936170 (700 3900);
PAINT GREEN (700 3900);
DISPLAY INVISIBLE (700 3900);
FORCEADD TAP..6
R 2
(700 3800);
FORCEPROP 3 LASTPIN (650 3800) SIG_NAME M_C_DQS_DP<3>
J 0
(660 3810);
DISPLAY 0.659574 (660 3810);
PAINT MONO (660 3810);
DISPLAY INVISIBLE (660 3810);
FORCEPROP 1 LASTPIN (650 3800) BN 3
J 2
(700 3810);
DISPLAY 0.617021 (700 3810);
PAINT PINK (700 3810);
FORCEPROP 2 LAST CDS_LIB mstr_standard
J 0
(700 3800);
DISPLAY 0.787234 (700 3800);
PAINT MONO (700 3800);
DISPLAY INVISIBLE (700 3800);
FORCEPROP 1 LAST BODY_TYPE PLUMBING
J 2
(700 3750);
DISPLAY 1.234043 (700 3750);
PAINT GREEN (700 3750);
DISPLAY INVISIBLE (700 3750);
FORCEPROP 1 LAST HDL_TAP TRUE
J 2
(375 3675);
DISPLAY 1.234043 (375 3675);
PAINT GREEN (375 3675);
DISPLAY INVISIBLE (375 3675);
FORCEPROP 1 LAST PATH I34
J 2
(700 3800);
DISPLAY 0.936170 (700 3800);
PAINT GREEN (700 3800);
DISPLAY INVISIBLE (700 3800);
FORCEADD TAP..6
R 2
(900 3550);
FORCEPROP 3 LASTPIN (850 3550) SIG_NAME M_C_DQS_DN<1>
J 0
(860 3560);
DISPLAY 0.659574 (860 3560);
PAINT MONO (860 3560);
DISPLAY INVISIBLE (860 3560);
FORCEPROP 1 LASTPIN (850 3550) BN 1
J 2
(900 3560);
DISPLAY 0.617021 (900 3560);
PAINT PINK (900 3560);
FORCEPROP 2 LAST CDS_LIB mstr_standard
J 0
(900 3550);
DISPLAY 0.787234 (900 3550);
PAINT MONO (900 3550);
DISPLAY INVISIBLE (900 3550);
FORCEPROP 1 LAST BODY_TYPE PLUMBING
J 2
(900 3500);
DISPLAY 1.234043 (900 3500);
PAINT GREEN (900 3500);
DISPLAY INVISIBLE (900 3500);
FORCEPROP 1 LAST HDL_TAP TRUE
J 2
(575 3425);
DISPLAY 1.234043 (575 3425);
PAINT GREEN (575 3425);
DISPLAY INVISIBLE (575 3425);
FORCEPROP 1 LAST PATH I35
J 2
(900 3550);
DISPLAY 0.936170 (900 3550);
PAINT GREEN (900 3550);
DISPLAY INVISIBLE (900 3550);
FORCEADD TAP..6
R 2
(900 3650);
FORCEPROP 3 LASTPIN (850 3650) SIG_NAME M_C_DQS_DN<2>
J 0
(860 3660);
DISPLAY 0.659574 (860 3660);
PAINT MONO (860 3660);
DISPLAY INVISIBLE (860 3660);
FORCEPROP 1 LASTPIN (850 3650) BN 2
J 2
(900 3660);
DISPLAY 0.617021 (900 3660);
PAINT PINK (900 3660);
FORCEPROP 2 LAST CDS_LIB mstr_standard
J 0
(900 3650);
DISPLAY 0.787234 (900 3650);
PAINT MONO (900 3650);
DISPLAY INVISIBLE (900 3650);
FORCEPROP 1 LAST BODY_TYPE PLUMBING
J 2
(900 3600);
DISPLAY 1.234043 (900 3600);
PAINT GREEN (900 3600);
DISPLAY INVISIBLE (900 3600);
FORCEPROP 1 LAST HDL_TAP TRUE
J 2
(575 3525);
DISPLAY 1.234043 (575 3525);
PAINT GREEN (575 3525);
DISPLAY INVISIBLE (575 3525);
FORCEPROP 1 LAST PATH I36
J 2
(900 3650);
DISPLAY 0.936170 (900 3650);
PAINT GREEN (900 3650);
DISPLAY INVISIBLE (900 3650);
FORCEADD TAP..6
R 2
(900 3750);
FORCEPROP 3 LASTPIN (850 3750) SIG_NAME M_C_DQS_DN<3>
J 0
(860 3760);
DISPLAY 0.659574 (860 3760);
PAINT MONO (860 3760);
DISPLAY INVISIBLE (860 3760);
FORCEPROP 1 LASTPIN (850 3750) BN 3
J 2
(900 3760);
DISPLAY 0.617021 (900 3760);
PAINT PINK (900 3760);
FORCEPROP 2 LAST CDS_LIB mstr_standard
J 0
(900 3750);
DISPLAY 0.787234 (900 3750);
PAINT MONO (900 3750);
DISPLAY INVISIBLE (900 3750);
FORCEPROP 1 LAST BODY_TYPE PLUMBING
J 2
(900 3700);
DISPLAY 1.234043 (900 3700);
PAINT GREEN (900 3700);
DISPLAY INVISIBLE (900 3700);
FORCEPROP 1 LAST HDL_TAP TRUE
J 2
(575 3625);
DISPLAY 1.234043 (575 3625);
PAINT GREEN (575 3625);
DISPLAY INVISIBLE (575 3625);
FORCEPROP 1 LAST PATH I37
J 2
(900 3750);
DISPLAY 0.936170 (900 3750);
PAINT GREEN (900 3750);
DISPLAY INVISIBLE (900 3750);
FORCEADD TAP..6
R 2
(700 3700);
FORCEPROP 3 LASTPIN (650 3700) SIG_NAME M_C_DQS_DP<2>
J 0
(660 3710);
DISPLAY 0.659574 (660 3710);
PAINT MONO (660 3710);
DISPLAY INVISIBLE (660 3710);
FORCEPROP 1 LASTPIN (650 3700) BN 2
J 2
(700 3710);
DISPLAY 0.617021 (700 3710);
PAINT PINK (700 3710);
FORCEPROP 2 LAST CDS_LIB mstr_standard
J 0
(700 3700);
DISPLAY 0.787234 (700 3700);
PAINT MONO (700 3700);
DISPLAY INVISIBLE (700 3700);
FORCEPROP 1 LAST BODY_TYPE PLUMBING
J 2
(700 3650);
DISPLAY 1.234043 (700 3650);
PAINT GREEN (700 3650);
DISPLAY INVISIBLE (700 3650);
FORCEPROP 1 LAST HDL_TAP TRUE
J 2
(375 3575);
DISPLAY 1.234043 (375 3575);
PAINT GREEN (375 3575);
DISPLAY INVISIBLE (375 3575);
FORCEPROP 1 LAST PATH I38
J 2
(700 3700);
DISPLAY 0.936170 (700 3700);
PAINT GREEN (700 3700);
DISPLAY INVISIBLE (700 3700);
FORCEADD TAP..6
R 2
(700 3600);
FORCEPROP 3 LASTPIN (650 3600) SIG_NAME M_C_DQS_DP<1>
J 0
(660 3610);
DISPLAY 0.659574 (660 3610);
PAINT MONO (660 3610);
DISPLAY INVISIBLE (660 3610);
FORCEPROP 1 LASTPIN (650 3600) BN 1
J 2
(700 3610);
DISPLAY 0.617021 (700 3610);
PAINT PINK (700 3610);
FORCEPROP 2 LAST CDS_LIB mstr_standard
J 0
(700 3600);
DISPLAY 0.787234 (700 3600);
PAINT MONO (700 3600);
DISPLAY INVISIBLE (700 3600);
FORCEPROP 1 LAST BODY_TYPE PLUMBING
J 2
(700 3550);
DISPLAY 1.234043 (700 3550);
PAINT GREEN (700 3550);
DISPLAY INVISIBLE (700 3550);
FORCEPROP 1 LAST HDL_TAP TRUE
J 2
(375 3475);
DISPLAY 1.234043 (375 3475);
PAINT GREEN (375 3475);
DISPLAY INVISIBLE (375 3475);
FORCEPROP 1 LAST PATH I39
J 2
(700 3600);
DISPLAY 0.936170 (700 3600);
PAINT GREEN (700 3600);
DISPLAY INVISIBLE (700 3600);
FORCEADD TAP..6
R 2
(700 5200);
FORCEPROP 3 LASTPIN (650 5200) SIG_NAME M_C_DQS_DP<17>
J 0
(660 5210);
DISPLAY 0.659574 (660 5210);
PAINT MONO (660 5210);
DISPLAY INVISIBLE (660 5210);
FORCEPROP 1 LASTPIN (650 5200) BN 17
J 2
(700 5210);
DISPLAY 0.617021 (700 5210);
PAINT PINK (700 5210);
FORCEPROP 2 LAST CDS_LIB mstr_standard
J 2
(700 5200);
DISPLAY 0.787234 (700 5200);
PAINT MONO (700 5200);
DISPLAY INVISIBLE (700 5200);
FORCEPROP 1 LAST BODY_TYPE PLUMBING
J 2
(700 5150);
DISPLAY 1.234043 (700 5150);
PAINT GREEN (700 5150);
DISPLAY INVISIBLE (700 5150);
FORCEPROP 1 LAST HDL_TAP TRUE
J 2
(375 5075);
DISPLAY 1.234043 (375 5075);
PAINT GREEN (375 5075);
DISPLAY INVISIBLE (375 5075);
FORCEPROP 1 LAST PATH I4
J 2
(700 5200);
DISPLAY 0.936170 (700 5200);
PAINT GREEN (700 5200);
DISPLAY INVISIBLE (700 5200);
FORCEADD TAP..6
R 2
(900 3450);
FORCEPROP 3 LASTPIN (850 3450) SIG_NAME M_C_DQS_DN<0>
J 0
(860 3460);
DISPLAY 0.659574 (860 3460);
PAINT MONO (860 3460);
DISPLAY INVISIBLE (860 3460);
FORCEPROP 1 LASTPIN (850 3450) BN 0
J 2
(900 3460);
DISPLAY 0.617021 (900 3460);
PAINT PINK (900 3460);
FORCEPROP 2 LAST CDS_LIB mstr_standard
J 0
(900 3450);
DISPLAY 0.787234 (900 3450);
PAINT MONO (900 3450);
DISPLAY INVISIBLE (900 3450);
FORCEPROP 1 LAST BODY_TYPE PLUMBING
J 2
(900 3400);
DISPLAY 1.234043 (900 3400);
PAINT GREEN (900 3400);
DISPLAY INVISIBLE (900 3400);
FORCEPROP 1 LAST HDL_TAP TRUE
J 2
(575 3325);
DISPLAY 1.234043 (575 3325);
PAINT GREEN (575 3325);
DISPLAY INVISIBLE (575 3325);
FORCEPROP 1 LAST PATH I40
J 2
(900 3450);
DISPLAY 0.936170 (900 3450);
PAINT GREEN (900 3450);
DISPLAY INVISIBLE (900 3450);
FORCEADD TAP..6
R 2
(700 3500);
FORCEPROP 3 LASTPIN (650 3500) SIG_NAME M_C_DQS_DP<0>
J 0
(660 3510);
DISPLAY 0.659574 (660 3510);
PAINT MONO (660 3510);
DISPLAY INVISIBLE (660 3510);
FORCEPROP 1 LASTPIN (650 3500) BN 0
J 2
(700 3510);
DISPLAY 0.617021 (700 3510);
PAINT PINK (700 3510);
FORCEPROP 2 LAST CDS_LIB mstr_standard
J 0
(700 3500);
DISPLAY 0.787234 (700 3500);
PAINT MONO (700 3500);
DISPLAY INVISIBLE (700 3500);
FORCEPROP 1 LAST BODY_TYPE PLUMBING
J 2
(700 3450);
DISPLAY 1.234043 (700 3450);
PAINT GREEN (700 3450);
DISPLAY INVISIBLE (700 3450);
FORCEPROP 1 LAST HDL_TAP TRUE
J 2
(375 3375);
DISPLAY 1.234043 (375 3375);
PAINT GREEN (375 3375);
DISPLAY INVISIBLE (375 3375);
FORCEPROP 1 LAST PATH I41
J 2
(700 3500);
DISPLAY 0.936170 (700 3500);
PAINT GREEN (700 3500);
DISPLAY INVISIBLE (700 3500);
FORCEADD SCONN288_H44441004..3
(1800 2650);
FORCEPROP 1 LAST LOCATION J4G3
J 0
(1350 4050);
DISPLAY 0.617021 (1350 4050);
PAINT AQUA (1350 4050);
FORCEPROP 1 LAST PART_NUMBER H44441-004
J 0
(1350 1300);
DISPLAY 0.617021 (1350 1300);
PAINT BLUE (1350 1300);
FORCEPROP 1 LAST MATERIAL SCONN
J 0
(1350 4000);
DISPLAY 0.617021 (1350 4000);
PAINT SKYBLUE (1350 4000);
FORCEPROP 2 LASTPIN (1300 3800) $PN 2
J 2
(1290 3810);
DISPLAY 0.617021 (1290 3810);
PAINT ORANGE (1290 3810);
FORCEPROP 2 LASTPIN (1300 3750) $PN 4
J 2
(1290 3760);
DISPLAY 0.617021 (1290 3760);
PAINT ORANGE (1290 3760);
FORCEPROP 2 LASTPIN (1300 3700) $PN 6
J 2
(1290 3710);
DISPLAY 0.617021 (1290 3710);
PAINT ORANGE (1290 3710);
FORCEPROP 2 LASTPIN (1300 3650) $PN 9
J 2
(1290 3660);
DISPLAY 0.617021 (1290 3660);
PAINT ORANGE (1290 3660);
FORCEPROP 2 LASTPIN (1300 3600) $PN 11
J 2
(1290 3610);
DISPLAY 0.617021 (1290 3610);
PAINT ORANGE (1290 3610);
FORCEPROP 2 LASTPIN (1300 3550) $PN 13
J 2
(1290 3560);
DISPLAY 0.617021 (1290 3560);
PAINT ORANGE (1290 3560);
FORCEPROP 2 LASTPIN (1300 3500) $PN 15
J 2
(1290 3510);
DISPLAY 0.617021 (1290 3510);
PAINT ORANGE (1290 3510);
FORCEPROP 2 LASTPIN (1300 3450) $PN 17
J 2
(1290 3460);
DISPLAY 0.617021 (1290 3460);
PAINT ORANGE (1290 3460);
FORCEPROP 2 LASTPIN (1300 3400) $PN 20
J 2
(1290 3410);
DISPLAY 0.617021 (1290 3410);
PAINT ORANGE (1290 3410);
FORCEPROP 2 LASTPIN (1300 3350) $PN 22
J 2
(1290 3360);
DISPLAY 0.617021 (1290 3360);
PAINT ORANGE (1290 3360);
FORCEPROP 2 LASTPIN (1300 3300) $PN 24
J 2
(1290 3310);
DISPLAY 0.617021 (1290 3310);
PAINT ORANGE (1290 3310);
FORCEPROP 2 LASTPIN (1300 3250) $PN 26
J 2
(1290 3260);
DISPLAY 0.617021 (1290 3260);
PAINT ORANGE (1290 3260);
FORCEPROP 2 LASTPIN (1300 3200) $PN 28
J 2
(1290 3210);
DISPLAY 0.617021 (1290 3210);
PAINT ORANGE (1290 3210);
FORCEPROP 2 LASTPIN (1300 3150) $PN 31
J 2
(1290 3160);
DISPLAY 0.617021 (1290 3160);
PAINT ORANGE (1290 3160);
FORCEPROP 2 LASTPIN (1300 3100) $PN 33
J 2
(1290 3110);
DISPLAY 0.617021 (1290 3110);
PAINT ORANGE (1290 3110);
FORCEPROP 2 LASTPIN (1300 3050) $PN 35
J 2
(1290 3060);
DISPLAY 0.617021 (1290 3060);
PAINT ORANGE (1290 3060);
FORCEPROP 2 LASTPIN (1300 3000) $PN 37
J 2
(1290 3010);
DISPLAY 0.617021 (1290 3010);
PAINT ORANGE (1290 3010);
FORCEPROP 2 LASTPIN (1300 2950) $PN 39
J 2
(1290 2960);
DISPLAY 0.617021 (1290 2960);
PAINT ORANGE (1290 2960);
FORCEPROP 2 LASTPIN (1300 2900) $PN 42
J 2
(1290 2910);
DISPLAY 0.617021 (1290 2910);
PAINT ORANGE (1290 2910);
FORCEPROP 2 LASTPIN (1300 2850) $PN 44
J 2
(1290 2860);
DISPLAY 0.617021 (1290 2860);
PAINT ORANGE (1290 2860);
FORCEPROP 2 LASTPIN (1300 2800) $PN 46
J 2
(1290 2810);
DISPLAY 0.617021 (1290 2810);
PAINT ORANGE (1290 2810);
FORCEPROP 2 LASTPIN (1300 2750) $PN 48
J 2
(1290 2760);
DISPLAY 0.617021 (1290 2760);
PAINT ORANGE (1290 2760);
FORCEPROP 2 LASTPIN (1300 2700) $PN 50
J 2
(1290 2710);
DISPLAY 0.617021 (1290 2710);
PAINT ORANGE (1290 2710);
FORCEPROP 2 LASTPIN (1300 2650) $PN 53
J 2
(1290 2660);
DISPLAY 0.617021 (1290 2660);
PAINT ORANGE (1290 2660);
FORCEPROP 2 LASTPIN (1300 2600) $PN 55
J 2
(1290 2610);
DISPLAY 0.617021 (1290 2610);
PAINT ORANGE (1290 2610);
FORCEPROP 2 LASTPIN (1300 2550) $PN 57
J 2
(1290 2560);
DISPLAY 0.617021 (1290 2560);
PAINT ORANGE (1290 2560);
FORCEPROP 2 LASTPIN (1300 2500) $PN 94
J 2
(1290 2510);
DISPLAY 0.617021 (1290 2510);
PAINT ORANGE (1290 2510);
FORCEPROP 2 LASTPIN (1300 2450) $PN 96
J 2
(1290 2460);
DISPLAY 0.617021 (1290 2460);
PAINT ORANGE (1290 2460);
FORCEPROP 2 LASTPIN (1300 2400) $PN 98
J 2
(1290 2410);
DISPLAY 0.617021 (1290 2410);
PAINT ORANGE (1290 2410);
FORCEPROP 2 LASTPIN (1300 2350) $PN 101
J 2
(1290 2360);
DISPLAY 0.617021 (1290 2360);
PAINT ORANGE (1290 2360);
FORCEPROP 2 LASTPIN (1300 2300) $PN 103
J 2
(1290 2310);
DISPLAY 0.617021 (1290 2310);
PAINT ORANGE (1290 2310);
FORCEPROP 2 LASTPIN (1300 2250) $PN 105
J 2
(1290 2260);
DISPLAY 0.617021 (1290 2260);
PAINT ORANGE (1290 2260);
FORCEPROP 2 LASTPIN (1300 2200) $PN 107
J 2
(1290 2210);
DISPLAY 0.617021 (1290 2210);
PAINT ORANGE (1290 2210);
FORCEPROP 2 LASTPIN (1300 2150) $PN 109
J 2
(1290 2160);
DISPLAY 0.617021 (1290 2160);
PAINT ORANGE (1290 2160);
FORCEPROP 2 LASTPIN (1300 2100) $PN 112
J 2
(1290 2110);
DISPLAY 0.617021 (1290 2110);
PAINT ORANGE (1290 2110);
FORCEPROP 2 LASTPIN (1300 2050) $PN 114
J 2
(1290 2060);
DISPLAY 0.617021 (1290 2060);
PAINT ORANGE (1290 2060);
FORCEPROP 2 LASTPIN (1300 2000) $PN 116
J 2
(1290 2010);
DISPLAY 0.617021 (1290 2010);
PAINT ORANGE (1290 2010);
FORCEPROP 2 LASTPIN (1300 1950) $PN 118
J 2
(1290 1960);
DISPLAY 0.617021 (1290 1960);
PAINT ORANGE (1290 1960);
FORCEPROP 2 LASTPIN (1300 1900) $PN 120
J 2
(1290 1910);
DISPLAY 0.617021 (1290 1910);
PAINT ORANGE (1290 1910);
FORCEPROP 2 LASTPIN (1300 1850) $PN 123
J 2
(1290 1860);
DISPLAY 0.617021 (1290 1860);
PAINT ORANGE (1290 1860);
FORCEPROP 2 LASTPIN (1300 1800) $PN 125
J 2
(1290 1810);
DISPLAY 0.617021 (1290 1810);
PAINT ORANGE (1290 1810);
FORCEPROP 2 LASTPIN (1300 1750) $PN 127
J 2
(1290 1760);
DISPLAY 0.617021 (1290 1760);
PAINT ORANGE (1290 1760);
FORCEPROP 2 LASTPIN (1300 1700) $PN 129
J 2
(1290 1710);
DISPLAY 0.617021 (1290 1710);
PAINT ORANGE (1290 1710);
FORCEPROP 2 LASTPIN (1300 1650) $PN 131
J 2
(1290 1660);
DISPLAY 0.617021 (1290 1660);
PAINT ORANGE (1290 1660);
FORCEPROP 2 LASTPIN (1300 1600) $PN 134
J 2
(1290 1610);
DISPLAY 0.617021 (1290 1610);
PAINT ORANGE (1290 1610);
FORCEPROP 2 LASTPIN (1300 1550) $PN 136
J 2
(1290 1560);
DISPLAY 0.617021 (1290 1560);
PAINT ORANGE (1290 1560);
FORCEPROP 2 LASTPIN (1300 1500) $PN 138
J 2
(1290 1510);
DISPLAY 0.617021 (1290 1510);
PAINT ORANGE (1290 1510);
FORCEPROP 2 LASTPIN (2300 3800) $PN 147
J 0
(2310 3810);
DISPLAY 0.617021 (2310 3810);
PAINT ORANGE (2310 3810);
FORCEPROP 2 LASTPIN (2300 3750) $PN 149
J 0
(2310 3760);
DISPLAY 0.617021 (2310 3760);
PAINT ORANGE (2310 3760);
FORCEPROP 2 LASTPIN (2300 3700) $PN 151
J 0
(2310 3710);
DISPLAY 0.617021 (2310 3710);
PAINT ORANGE (2310 3710);
FORCEPROP 2 LASTPIN (2300 3650) $PN 154
J 0
(2310 3660);
DISPLAY 0.617021 (2310 3660);
PAINT ORANGE (2310 3660);
FORCEPROP 2 LASTPIN (2300 3600) $PN 156
J 0
(2310 3610);
DISPLAY 0.617021 (2310 3610);
PAINT ORANGE (2310 3610);
FORCEPROP 2 LASTPIN (2300 3550) $PN 158
J 0
(2310 3560);
DISPLAY 0.617021 (2310 3560);
PAINT ORANGE (2310 3560);
FORCEPROP 2 LASTPIN (2300 3500) $PN 160
J 0
(2310 3510);
DISPLAY 0.617021 (2310 3510);
PAINT ORANGE (2310 3510);
FORCEPROP 2 LASTPIN (2300 3450) $PN 162
J 0
(2310 3460);
DISPLAY 0.617021 (2310 3460);
PAINT ORANGE (2310 3460);
FORCEPROP 2 LASTPIN (2300 3400) $PN 165
J 0
(2310 3410);
DISPLAY 0.617021 (2310 3410);
PAINT ORANGE (2310 3410);
FORCEPROP 2 LASTPIN (2300 3350) $PN 167
J 0
(2310 3360);
DISPLAY 0.617021 (2310 3360);
PAINT ORANGE (2310 3360);
FORCEPROP 2 LASTPIN (2300 3300) $PN 169
J 0
(2310 3310);
DISPLAY 0.617021 (2310 3310);
PAINT ORANGE (2310 3310);
FORCEPROP 2 LASTPIN (2300 3250) $PN 171
J 0
(2310 3260);
DISPLAY 0.617021 (2310 3260);
PAINT ORANGE (2310 3260);
FORCEPROP 2 LASTPIN (2300 3200) $PN 173
J 0
(2310 3210);
DISPLAY 0.617021 (2310 3210);
PAINT ORANGE (2310 3210);
FORCEPROP 2 LASTPIN (2300 3150) $PN 176
J 0
(2310 3160);
DISPLAY 0.617021 (2310 3160);
PAINT ORANGE (2310 3160);
FORCEPROP 2 LASTPIN (2300 3100) $PN 178
J 0
(2310 3110);
DISPLAY 0.617021 (2310 3110);
PAINT ORANGE (2310 3110);
FORCEPROP 2 LASTPIN (2300 3050) $PN 180
J 0
(2310 3060);
DISPLAY 0.617021 (2310 3060);
PAINT ORANGE (2310 3060);
FORCEPROP 2 LASTPIN (2300 3000) $PN 182
J 0
(2310 3010);
DISPLAY 0.617021 (2310 3010);
PAINT ORANGE (2310 3010);
FORCEPROP 2 LASTPIN (2300 2950) $PN 184
J 0
(2310 2960);
DISPLAY 0.617021 (2310 2960);
PAINT ORANGE (2310 2960);
FORCEPROP 2 LASTPIN (2300 2900) $PN 187
J 0
(2310 2910);
DISPLAY 0.617021 (2310 2910);
PAINT ORANGE (2310 2910);
FORCEPROP 2 LASTPIN (2300 2850) $PN 189
J 0
(2310 2860);
DISPLAY 0.617021 (2310 2860);
PAINT ORANGE (2310 2860);
FORCEPROP 2 LASTPIN (2300 2800) $PN 191
J 0
(2310 2810);
DISPLAY 0.617021 (2310 2810);
PAINT ORANGE (2310 2810);
FORCEPROP 2 LASTPIN (2300 2750) $PN 193
J 0
(2310 2760);
DISPLAY 0.617021 (2310 2760);
PAINT ORANGE (2310 2760);
FORCEPROP 2 LASTPIN (2300 2700) $PN 195
J 0
(2310 2710);
DISPLAY 0.617021 (2310 2710);
PAINT ORANGE (2310 2710);
FORCEPROP 2 LASTPIN (2300 2650) $PN 198
J 0
(2310 2660);
DISPLAY 0.617021 (2310 2660);
PAINT ORANGE (2310 2660);
FORCEPROP 2 LASTPIN (2300 2600) $PN 200
J 0
(2310 2610);
DISPLAY 0.617021 (2310 2610);
PAINT ORANGE (2310 2610);
FORCEPROP 2 LASTPIN (2300 2550) $PN 202
J 0
(2310 2560);
DISPLAY 0.617021 (2310 2560);
PAINT ORANGE (2310 2560);
FORCEPROP 2 LASTPIN (2300 2500) $PN 239
J 0
(2310 2510);
DISPLAY 0.617021 (2310 2510);
PAINT ORANGE (2310 2510);
FORCEPROP 2 LASTPIN (2300 2450) $PN 241
J 0
(2310 2460);
DISPLAY 0.617021 (2310 2460);
PAINT ORANGE (2310 2460);
FORCEPROP 2 LASTPIN (2300 2400) $PN 243
J 0
(2310 2410);
DISPLAY 0.617021 (2310 2410);
PAINT ORANGE (2310 2410);
FORCEPROP 2 LASTPIN (2300 2350) $PN 246
J 0
(2310 2360);
DISPLAY 0.617021 (2310 2360);
PAINT ORANGE (2310 2360);
FORCEPROP 2 LASTPIN (2300 2300) $PN 248
J 0
(2310 2310);
DISPLAY 0.617021 (2310 2310);
PAINT ORANGE (2310 2310);
FORCEPROP 2 LASTPIN (2300 2250) $PN 250
J 0
(2310 2260);
DISPLAY 0.617021 (2310 2260);
PAINT ORANGE (2310 2260);
FORCEPROP 2 LASTPIN (2300 2200) $PN 252
J 0
(2310 2210);
DISPLAY 0.617021 (2310 2210);
PAINT ORANGE (2310 2210);
FORCEPROP 2 LASTPIN (2300 2150) $PN 254
J 0
(2310 2160);
DISPLAY 0.617021 (2310 2160);
PAINT ORANGE (2310 2160);
FORCEPROP 2 LASTPIN (2300 2100) $PN 257
J 0
(2310 2110);
DISPLAY 0.617021 (2310 2110);
PAINT ORANGE (2310 2110);
FORCEPROP 2 LASTPIN (2300 2050) $PN 259
J 0
(2310 2060);
DISPLAY 0.617021 (2310 2060);
PAINT ORANGE (2310 2060);
FORCEPROP 2 LASTPIN (2300 2000) $PN 261
J 0
(2310 2010);
DISPLAY 0.617021 (2310 2010);
PAINT ORANGE (2310 2010);
FORCEPROP 2 LASTPIN (2300 1950) $PN 263
J 0
(2310 1960);
DISPLAY 0.617021 (2310 1960);
PAINT ORANGE (2310 1960);
FORCEPROP 2 LASTPIN (2300 1900) $PN 265
J 0
(2310 1910);
DISPLAY 0.617021 (2310 1910);
PAINT ORANGE (2310 1910);
FORCEPROP 2 LASTPIN (2300 1850) $PN 268
J 0
(2310 1860);
DISPLAY 0.617021 (2310 1860);
PAINT ORANGE (2310 1860);
FORCEPROP 2 LASTPIN (2300 1800) $PN 270
J 0
(2310 1810);
DISPLAY 0.617021 (2310 1810);
PAINT ORANGE (2310 1810);
FORCEPROP 2 LASTPIN (2300 1750) $PN 272
J 0
(2310 1760);
DISPLAY 0.617021 (2310 1760);
PAINT ORANGE (2310 1760);
FORCEPROP 2 LASTPIN (2300 1700) $PN 274
J 0
(2310 1710);
DISPLAY 0.617021 (2310 1710);
PAINT ORANGE (2310 1710);
FORCEPROP 2 LASTPIN (2300 1650) $PN 276
J 0
(2310 1660);
DISPLAY 0.617021 (2310 1660);
PAINT ORANGE (2310 1660);
FORCEPROP 2 LASTPIN (2300 1600) $PN 279
J 0
(2310 1610);
DISPLAY 0.617021 (2310 1610);
PAINT ORANGE (2310 1610);
FORCEPROP 2 LASTPIN (2300 1550) $PN 281
J 0
(2310 1560);
DISPLAY 0.617021 (2310 1560);
PAINT ORANGE (2310 1560);
FORCEPROP 2 LASTPIN (2300 1500) $PN 283
J 0
(2310 1510);
DISPLAY 0.617021 (2310 1510);
PAINT ORANGE (2310 1510);
FORCEPROP 1 LAST PACK_TYPE PIP
J 0
(1350 4100);
PAINT SKYBLUE (1350 4100);
DISPLAY INVISIBLE (1350 4100);
FORCEPROP 2 LAST BOM_COST MEM
J 0
(1800 2650);
PAINT ORANGE (1800 2650);
DISPLAY INVISIBLE (1800 2650);
FORCEPROP 2 LAST CDS_LIB mstr_sconn
J 0
(1800 2650);
PAINT ORANGE (1800 2650);
DISPLAY INVISIBLE (1800 2650);
FORCEPROP 2 LAST SEC_TYPE PIP
J 0
(1350 4100);
DISPLAY 1.021277 (1350 4100);
PAINT ORANGE (1350 4100);
DISPLAY INVISIBLE (1350 4100);
FORCEPROP 2 LAST SEC 3
J 0
(1350 4100);
DISPLAY 0.680851 (1350 4100);
PAINT MONO (1350 4100);
DISPLAY INVISIBLE (1350 4100);
FORCEPROP 2 LAST CDS_LOCATION J4G3
J 0
(1350 4050);
DISPLAY 0.617021 (1350 4050);
PAINT AQUA (1350 4050);
DISPLAY INVISIBLE (1350 4050);
FORCEPROP 1 LAST PATH I43
J 0
(1800 4000);
PAINT GREEN (1800 4000);
DISPLAY INVISIBLE (1800 4000);
FORCEPROP 2 LAST ROOM DDR4_CH_C
J 0
(1800 2650);
PAINT ORANGE (1800 2650);
DISPLAY INVISIBLE (1800 2650);
FORCEADD GND..1
R 2
(1100 1350);
FORCEPROP 3 LASTPIN (1100 1400) SIG_NAME GND\g
J 0
(1110 1410);
DISPLAY 0.659574 (1110 1410);
PAINT MONO (1110 1410);
DISPLAY INVISIBLE (1110 1410);
FORCEPROP 1 LAST VOLTAGE 0
J 0
(1100 1350);
PAINT SKYBLUE (1100 1350);
DISPLAY INVISIBLE (1100 1350);
FORCEPROP 2 LAST CDS_LIB mstr_symbols
J 0
(1100 1350);
DISPLAY 0.787234 (1100 1350);
PAINT MONO (1100 1350);
DISPLAY INVISIBLE (1100 1350);
FORCEPROP 1 LAST SIZE 1B
J 2
(1025 1300);
DISPLAY 1.170213 (1025 1300);
PAINT GREEN (1025 1300);
DISPLAY INVISIBLE (1025 1300);
FORCEPROP 2 LAST BOM_COST MEM
J 0
(1100 1355);
PAINT ORANGE (1100 1355);
DISPLAY INVISIBLE (1100 1355);
FORCEPROP 1 LAST BODY_TYPE PLUMBING
J 2
(1145 1307);
DISPLAY 0.340426 (1145 1307);
PAINT GREEN (1145 1307);
DISPLAY INVISIBLE (1145 1307);
FORCEPROP 1 LAST PATH I44
J 2
(1025 1350);
DISPLAY 0.936170 (1025 1350);
PAINT GREEN (1025 1350);
DISPLAY INVISIBLE (1025 1350);
FORCEPROP 2 LAST ROOM DDR4_CH_A
J 0
(1100 1355);
PAINT ORANGE (1100 1355);
DISPLAY INVISIBLE (1100 1355);
FORCEPROP 1 LAST HDL_POWER GND
J 2
(1100 1500);
DISPLAY 0.553191 (1100 1500);
PAINT GREEN (1100 1500);
DISPLAY INVISIBLE (1100 1500);
FORCEADD OFFPAGE..3
(-1150 4700);
FORCEPROP 2 LAST $XR0 25 
J 0
(-936 4700);
DISPLAY 0.638298 (-936 4700);
PAINT MONO (-936 4700);
FORCEPROP 2 LAST $XR1 48 
J 0
(-846 4700);
DISPLAY 0.638298 (-846 4700);
PAINT MONO (-846 4700);
FORCEPROP 2 LAST CDS_LIB mstr_standard
J 0
(-1150 4700);
DISPLAY 0.787234 (-1150 4700);
PAINT MONO (-1150 4700);
DISPLAY INVISIBLE (-1150 4700);
FORCEPROP 1 LAST OFFPAGE TRUE
J 0
(-825 4575);
DISPLAY 0.936170 (-825 4575);
PAINT GREEN (-825 4575);
DISPLAY INVISIBLE (-825 4575);
FORCEPROP 1 LAST COMMENT_BODY TRUE
J 0
(-1200 4600);
DISPLAY 0.936170 (-1200 4600);
PAINT GREEN (-1200 4600);
DISPLAY INVISIBLE (-1200 4600);
FORCEPROP 2 LAST PATH I45
J 0
(-950 4775);
DISPLAY 0.787234 (-950 4775);
PAINT MONO (-950 4775);
DISPLAY INVISIBLE (-950 4775);
FORCEADD TAP..6
R 2
(-1700 4650);
FORCEPROP 3 LASTPIN (-1750 4650) SIG_NAME M_C_DQ<62>
J 0
(-1740 4660);
DISPLAY 0.659574 (-1740 4660);
PAINT MONO (-1740 4660);
DISPLAY INVISIBLE (-1740 4660);
FORCEPROP 1 LASTPIN (-1750 4650) BN 62
J 2
(-1700 4660);
DISPLAY 0.617021 (-1700 4660);
PAINT PINK (-1700 4660);
FORCEPROP 2 LAST CDS_LIB mstr_standard
J 2
(-1700 4650);
DISPLAY 0.787234 (-1700 4650);
PAINT MONO (-1700 4650);
DISPLAY INVISIBLE (-1700 4650);
FORCEPROP 1 LAST BODY_TYPE PLUMBING
J 2
(-1700 4600);
DISPLAY 1.234043 (-1700 4600);
PAINT GREEN (-1700 4600);
DISPLAY INVISIBLE (-1700 4600);
FORCEPROP 1 LAST HDL_TAP TRUE
J 2
(-2025 4525);
DISPLAY 1.234043 (-2025 4525);
PAINT GREEN (-2025 4525);
DISPLAY INVISIBLE (-2025 4525);
FORCEPROP 1 LAST PATH I46
J 2
(-1700 4650);
DISPLAY 0.936170 (-1700 4650);
PAINT GREEN (-1700 4650);
DISPLAY INVISIBLE (-1700 4650);
FORCEADD TAP..6
R 2
(-1700 4600);
FORCEPROP 3 LASTPIN (-1750 4600) SIG_NAME M_C_DQ<63>
J 0
(-1740 4610);
DISPLAY 0.659574 (-1740 4610);
PAINT MONO (-1740 4610);
DISPLAY INVISIBLE (-1740 4610);
FORCEPROP 1 LASTPIN (-1750 4600) BN 63
J 2
(-1700 4610);
DISPLAY 0.617021 (-1700 4610);
PAINT PINK (-1700 4610);
FORCEPROP 2 LAST CDS_LIB mstr_standard
J 2
(-1700 4600);
DISPLAY 0.787234 (-1700 4600);
PAINT MONO (-1700 4600);
DISPLAY INVISIBLE (-1700 4600);
FORCEPROP 1 LAST BODY_TYPE PLUMBING
J 2
(-1700 4550);
DISPLAY 1.234043 (-1700 4550);
PAINT GREEN (-1700 4550);
DISPLAY INVISIBLE (-1700 4550);
FORCEPROP 1 LAST HDL_TAP TRUE
J 2
(-2025 4475);
DISPLAY 1.234043 (-2025 4475);
PAINT GREEN (-2025 4475);
DISPLAY INVISIBLE (-2025 4475);
FORCEPROP 1 LAST PATH I47
J 2
(-1700 4600);
DISPLAY 0.936170 (-1700 4600);
PAINT GREEN (-1700 4600);
DISPLAY INVISIBLE (-1700 4600);
FORCEADD TAP..6
R 2
(-1700 4450);
FORCEPROP 3 LASTPIN (-1750 4450) SIG_NAME M_C_DQ<58>
J 0
(-1740 4460);
DISPLAY 0.659574 (-1740 4460);
PAINT MONO (-1740 4460);
DISPLAY INVISIBLE (-1740 4460);
FORCEPROP 1 LASTPIN (-1750 4450) BN 58
J 2
(-1700 4460);
DISPLAY 0.617021 (-1700 4460);
PAINT PINK (-1700 4460);
FORCEPROP 2 LAST CDS_LIB mstr_standard
J 2
(-1700 4450);
DISPLAY 0.787234 (-1700 4450);
PAINT MONO (-1700 4450);
DISPLAY INVISIBLE (-1700 4450);
FORCEPROP 1 LAST BODY_TYPE PLUMBING
J 2
(-1700 4400);
DISPLAY 1.234043 (-1700 4400);
PAINT GREEN (-1700 4400);
DISPLAY INVISIBLE (-1700 4400);
FORCEPROP 1 LAST HDL_TAP TRUE
J 2
(-2025 4325);
DISPLAY 1.234043 (-2025 4325);
PAINT GREEN (-2025 4325);
DISPLAY INVISIBLE (-2025 4325);
FORCEPROP 1 LAST PATH I48
J 2
(-1700 4450);
DISPLAY 0.936170 (-1700 4450);
PAINT GREEN (-1700 4450);
DISPLAY INVISIBLE (-1700 4450);
FORCEADD TAP..6
R 2
(-1700 4500);
FORCEPROP 3 LASTPIN (-1750 4500) SIG_NAME M_C_DQ<61>
J 0
(-1740 4510);
DISPLAY 0.659574 (-1740 4510);
PAINT MONO (-1740 4510);
DISPLAY INVISIBLE (-1740 4510);
FORCEPROP 1 LASTPIN (-1750 4500) BN 61
J 2
(-1700 4510);
DISPLAY 0.617021 (-1700 4510);
PAINT PINK (-1700 4510);
FORCEPROP 2 LAST CDS_LIB mstr_standard
J 2
(-1700 4500);
DISPLAY 0.787234 (-1700 4500);
PAINT MONO (-1700 4500);
DISPLAY INVISIBLE (-1700 4500);
FORCEPROP 1 LAST BODY_TYPE PLUMBING
J 2
(-1700 4450);
DISPLAY 1.234043 (-1700 4450);
PAINT GREEN (-1700 4450);
DISPLAY INVISIBLE (-1700 4450);
FORCEPROP 1 LAST HDL_TAP TRUE
J 2
(-2025 4375);
DISPLAY 1.234043 (-2025 4375);
PAINT GREEN (-2025 4375);
DISPLAY INVISIBLE (-2025 4375);
FORCEPROP 1 LAST PATH I49
J 2
(-1700 4500);
DISPLAY 0.936170 (-1700 4500);
PAINT GREEN (-1700 4500);
DISPLAY INVISIBLE (-1700 4500);
FORCEADD TAP..6
R 2
(700 5100);
FORCEPROP 3 LASTPIN (650 5100) SIG_NAME M_C_DQS_DP<16>
J 0
(660 5110);
DISPLAY 0.659574 (660 5110);
PAINT MONO (660 5110);
DISPLAY INVISIBLE (660 5110);
FORCEPROP 1 LASTPIN (650 5100) BN 16
J 2
(700 5110);
DISPLAY 0.617021 (700 5110);
PAINT PINK (700 5110);
FORCEPROP 2 LAST CDS_LIB mstr_standard
J 0
(700 5100);
DISPLAY 0.787234 (700 5100);
PAINT MONO (700 5100);
DISPLAY INVISIBLE (700 5100);
FORCEPROP 1 LAST BODY_TYPE PLUMBING
J 2
(700 5050);
DISPLAY 1.234043 (700 5050);
PAINT GREEN (700 5050);
DISPLAY INVISIBLE (700 5050);
FORCEPROP 1 LAST HDL_TAP TRUE
J 2
(375 4975);
DISPLAY 1.234043 (375 4975);
PAINT GREEN (375 4975);
DISPLAY INVISIBLE (375 4975);
FORCEPROP 1 LAST PATH I5
J 2
(700 5100);
DISPLAY 0.936170 (700 5100);
PAINT GREEN (700 5100);
DISPLAY INVISIBLE (700 5100);
FORCEADD TAP..6
R 2
(-1700 4550);
FORCEPROP 3 LASTPIN (-1750 4550) SIG_NAME M_C_DQ<60>
J 0
(-1740 4560);
DISPLAY 0.659574 (-1740 4560);
PAINT MONO (-1740 4560);
DISPLAY INVISIBLE (-1740 4560);
FORCEPROP 1 LASTPIN (-1750 4550) BN 60
J 2
(-1700 4560);
DISPLAY 0.617021 (-1700 4560);
PAINT PINK (-1700 4560);
FORCEPROP 2 LAST CDS_LIB mstr_standard
J 2
(-1700 4550);
DISPLAY 0.787234 (-1700 4550);
PAINT MONO (-1700 4550);
DISPLAY INVISIBLE (-1700 4550);
FORCEPROP 1 LAST BODY_TYPE PLUMBING
J 2
(-1700 4500);
DISPLAY 1.234043 (-1700 4500);
PAINT GREEN (-1700 4500);
DISPLAY INVISIBLE (-1700 4500);
FORCEPROP 1 LAST HDL_TAP TRUE
J 2
(-2025 4425);
DISPLAY 1.234043 (-2025 4425);
PAINT GREEN (-2025 4425);
DISPLAY INVISIBLE (-2025 4425);
FORCEPROP 1 LAST PATH I50
J 2
(-1700 4550);
DISPLAY 0.936170 (-1700 4550);
PAINT GREEN (-1700 4550);
DISPLAY INVISIBLE (-1700 4550);
FORCEADD TAP..6
R 2
(-1700 4350);
FORCEPROP 3 LASTPIN (-1750 4350) SIG_NAME M_C_DQ<56>
J 0
(-1740 4360);
DISPLAY 0.659574 (-1740 4360);
PAINT MONO (-1740 4360);
DISPLAY INVISIBLE (-1740 4360);
FORCEPROP 1 LASTPIN (-1750 4350) BN 56
J 2
(-1700 4360);
DISPLAY 0.617021 (-1700 4360);
PAINT PINK (-1700 4360);
FORCEPROP 2 LAST CDS_LIB mstr_standard
J 2
(-1700 4350);
DISPLAY 0.787234 (-1700 4350);
PAINT MONO (-1700 4350);
DISPLAY INVISIBLE (-1700 4350);
FORCEPROP 1 LAST BODY_TYPE PLUMBING
J 2
(-1700 4300);
DISPLAY 1.234043 (-1700 4300);
PAINT GREEN (-1700 4300);
DISPLAY INVISIBLE (-1700 4300);
FORCEPROP 1 LAST HDL_TAP TRUE
J 2
(-2025 4225);
DISPLAY 1.234043 (-2025 4225);
PAINT GREEN (-2025 4225);
DISPLAY INVISIBLE (-2025 4225);
FORCEPROP 1 LAST PATH I51
J 2
(-1700 4350);
DISPLAY 0.936170 (-1700 4350);
PAINT GREEN (-1700 4350);
DISPLAY INVISIBLE (-1700 4350);
FORCEADD TAP..6
R 2
(-1700 4400);
FORCEPROP 3 LASTPIN (-1750 4400) SIG_NAME M_C_DQ<59>
J 0
(-1740 4410);
DISPLAY 0.659574 (-1740 4410);
PAINT MONO (-1740 4410);
DISPLAY INVISIBLE (-1740 4410);
FORCEPROP 1 LASTPIN (-1750 4400) BN 59
J 2
(-1700 4410);
DISPLAY 0.617021 (-1700 4410);
PAINT PINK (-1700 4410);
FORCEPROP 2 LAST CDS_LIB mstr_standard
J 2
(-1700 4400);
DISPLAY 0.787234 (-1700 4400);
PAINT MONO (-1700 4400);
DISPLAY INVISIBLE (-1700 4400);
FORCEPROP 1 LAST BODY_TYPE PLUMBING
J 2
(-1700 4350);
DISPLAY 1.234043 (-1700 4350);
PAINT GREEN (-1700 4350);
DISPLAY INVISIBLE (-1700 4350);
FORCEPROP 1 LAST HDL_TAP TRUE
J 2
(-2025 4275);
DISPLAY 1.234043 (-2025 4275);
PAINT GREEN (-2025 4275);
DISPLAY INVISIBLE (-2025 4275);
FORCEPROP 1 LAST PATH I52
J 2
(-1700 4400);
DISPLAY 0.936170 (-1700 4400);
PAINT GREEN (-1700 4400);
DISPLAY INVISIBLE (-1700 4400);
FORCEADD TAP..6
R 2
(-1700 4200);
FORCEPROP 3 LASTPIN (-1750 4200) SIG_NAME M_C_DQ<55>
J 0
(-1740 4210);
DISPLAY 0.659574 (-1740 4210);
PAINT MONO (-1740 4210);
DISPLAY INVISIBLE (-1740 4210);
FORCEPROP 1 LASTPIN (-1750 4200) BN 55
J 2
(-1700 4210);
DISPLAY 0.617021 (-1700 4210);
PAINT PINK (-1700 4210);
FORCEPROP 2 LAST CDS_LIB mstr_standard
J 2
(-1700 4200);
DISPLAY 0.787234 (-1700 4200);
PAINT MONO (-1700 4200);
DISPLAY INVISIBLE (-1700 4200);
FORCEPROP 1 LAST BODY_TYPE PLUMBING
J 2
(-1700 4150);
DISPLAY 1.234043 (-1700 4150);
PAINT GREEN (-1700 4150);
DISPLAY INVISIBLE (-1700 4150);
FORCEPROP 1 LAST HDL_TAP TRUE
J 2
(-2025 4075);
DISPLAY 1.234043 (-2025 4075);
PAINT GREEN (-2025 4075);
DISPLAY INVISIBLE (-2025 4075);
FORCEPROP 1 LAST PATH I53
J 2
(-1700 4200);
DISPLAY 0.936170 (-1700 4200);
PAINT GREEN (-1700 4200);
DISPLAY INVISIBLE (-1700 4200);
FORCEADD TAP..6
R 2
(-1700 4250);
FORCEPROP 3 LASTPIN (-1750 4250) SIG_NAME M_C_DQ<54>
J 0
(-1740 4260);
DISPLAY 0.659574 (-1740 4260);
PAINT MONO (-1740 4260);
DISPLAY INVISIBLE (-1740 4260);
FORCEPROP 1 LASTPIN (-1750 4250) BN 54
J 2
(-1700 4260);
DISPLAY 0.617021 (-1700 4260);
PAINT PINK (-1700 4260);
FORCEPROP 2 LAST CDS_LIB mstr_standard
J 2
(-1700 4250);
DISPLAY 0.787234 (-1700 4250);
PAINT MONO (-1700 4250);
DISPLAY INVISIBLE (-1700 4250);
FORCEPROP 1 LAST BODY_TYPE PLUMBING
J 2
(-1700 4200);
DISPLAY 1.234043 (-1700 4200);
PAINT GREEN (-1700 4200);
DISPLAY INVISIBLE (-1700 4200);
FORCEPROP 1 LAST HDL_TAP TRUE
J 2
(-2025 4125);
DISPLAY 1.234043 (-2025 4125);
PAINT GREEN (-2025 4125);
DISPLAY INVISIBLE (-2025 4125);
FORCEPROP 1 LAST PATH I54
J 2
(-1700 4250);
DISPLAY 0.936170 (-1700 4250);
PAINT GREEN (-1700 4250);
DISPLAY INVISIBLE (-1700 4250);
FORCEADD TAP..6
R 2
(-1700 4300);
FORCEPROP 3 LASTPIN (-1750 4300) SIG_NAME M_C_DQ<57>
J 0
(-1740 4310);
DISPLAY 0.659574 (-1740 4310);
PAINT MONO (-1740 4310);
DISPLAY INVISIBLE (-1740 4310);
FORCEPROP 1 LASTPIN (-1750 4300) BN 57
J 2
(-1700 4310);
DISPLAY 0.617021 (-1700 4310);
PAINT PINK (-1700 4310);
FORCEPROP 2 LAST CDS_LIB mstr_standard
J 2
(-1700 4300);
DISPLAY 0.787234 (-1700 4300);
PAINT MONO (-1700 4300);
DISPLAY INVISIBLE (-1700 4300);
FORCEPROP 1 LAST BODY_TYPE PLUMBING
J 2
(-1700 4250);
DISPLAY 1.234043 (-1700 4250);
PAINT GREEN (-1700 4250);
DISPLAY INVISIBLE (-1700 4250);
FORCEPROP 1 LAST HDL_TAP TRUE
J 2
(-2025 4175);
DISPLAY 1.234043 (-2025 4175);
PAINT GREEN (-2025 4175);
DISPLAY INVISIBLE (-2025 4175);
FORCEPROP 1 LAST PATH I55
J 2
(-1700 4300);
DISPLAY 0.936170 (-1700 4300);
PAINT GREEN (-1700 4300);
DISPLAY INVISIBLE (-1700 4300);
FORCEADD TAP..6
R 2
(-1700 4100);
FORCEPROP 3 LASTPIN (-1750 4100) SIG_NAME M_C_DQ<53>
J 0
(-1740 4110);
DISPLAY 0.659574 (-1740 4110);
PAINT MONO (-1740 4110);
DISPLAY INVISIBLE (-1740 4110);
FORCEPROP 1 LASTPIN (-1750 4100) BN 53
J 2
(-1700 4110);
DISPLAY 0.617021 (-1700 4110);
PAINT PINK (-1700 4110);
FORCEPROP 2 LAST CDS_LIB mstr_standard
J 2
(-1700 4100);
DISPLAY 0.787234 (-1700 4100);
PAINT MONO (-1700 4100);
DISPLAY INVISIBLE (-1700 4100);
FORCEPROP 1 LAST BODY_TYPE PLUMBING
J 2
(-1700 4050);
DISPLAY 1.234043 (-1700 4050);
PAINT GREEN (-1700 4050);
DISPLAY INVISIBLE (-1700 4050);
FORCEPROP 1 LAST HDL_TAP TRUE
J 2
(-2025 3975);
DISPLAY 1.234043 (-2025 3975);
PAINT GREEN (-2025 3975);
DISPLAY INVISIBLE (-2025 3975);
FORCEPROP 1 LAST PATH I56
J 2
(-1700 4100);
DISPLAY 0.936170 (-1700 4100);
PAINT GREEN (-1700 4100);
DISPLAY INVISIBLE (-1700 4100);
FORCEADD TAP..6
R 2
(-1700 4150);
FORCEPROP 3 LASTPIN (-1750 4150) SIG_NAME M_C_DQ<52>
J 0
(-1740 4160);
DISPLAY 0.659574 (-1740 4160);
PAINT MONO (-1740 4160);
DISPLAY INVISIBLE (-1740 4160);
FORCEPROP 1 LASTPIN (-1750 4150) BN 52
J 2
(-1700 4160);
DISPLAY 0.617021 (-1700 4160);
PAINT PINK (-1700 4160);
FORCEPROP 2 LAST CDS_LIB mstr_standard
J 2
(-1700 4150);
DISPLAY 0.787234 (-1700 4150);
PAINT MONO (-1700 4150);
DISPLAY INVISIBLE (-1700 4150);
FORCEPROP 1 LAST BODY_TYPE PLUMBING
J 2
(-1700 4100);
DISPLAY 1.234043 (-1700 4100);
PAINT GREEN (-1700 4100);
DISPLAY INVISIBLE (-1700 4100);
FORCEPROP 1 LAST HDL_TAP TRUE
J 2
(-2025 4025);
DISPLAY 1.234043 (-2025 4025);
PAINT GREEN (-2025 4025);
DISPLAY INVISIBLE (-2025 4025);
FORCEPROP 1 LAST PATH I57
J 2
(-1700 4150);
DISPLAY 0.936170 (-1700 4150);
PAINT GREEN (-1700 4150);
DISPLAY INVISIBLE (-1700 4150);
FORCEADD TAP..6
R 2
(-1700 4050);
FORCEPROP 3 LASTPIN (-1750 4050) SIG_NAME M_C_DQ<50>
J 0
(-1740 4060);
DISPLAY 0.659574 (-1740 4060);
PAINT MONO (-1740 4060);
DISPLAY INVISIBLE (-1740 4060);
FORCEPROP 1 LASTPIN (-1750 4050) BN 50
J 2
(-1700 4060);
DISPLAY 0.617021 (-1700 4060);
PAINT PINK (-1700 4060);
FORCEPROP 2 LAST CDS_LIB mstr_standard
J 2
(-1700 4050);
DISPLAY 0.787234 (-1700 4050);
PAINT MONO (-1700 4050);
DISPLAY INVISIBLE (-1700 4050);
FORCEPROP 1 LAST BODY_TYPE PLUMBING
J 2
(-1700 4000);
DISPLAY 1.234043 (-1700 4000);
PAINT GREEN (-1700 4000);
DISPLAY INVISIBLE (-1700 4000);
FORCEPROP 1 LAST HDL_TAP TRUE
J 2
(-2025 3925);
DISPLAY 1.234043 (-2025 3925);
PAINT GREEN (-2025 3925);
DISPLAY INVISIBLE (-2025 3925);
FORCEPROP 1 LAST PATH I58
J 2
(-1700 4050);
DISPLAY 0.936170 (-1700 4050);
PAINT GREEN (-1700 4050);
DISPLAY INVISIBLE (-1700 4050);
FORCEADD TAP..6
R 2
(-1700 4000);
FORCEPROP 3 LASTPIN (-1750 4000) SIG_NAME M_C_DQ<51>
J 0
(-1740 4010);
DISPLAY 0.659574 (-1740 4010);
PAINT MONO (-1740 4010);
DISPLAY INVISIBLE (-1740 4010);
FORCEPROP 1 LASTPIN (-1750 4000) BN 51
J 2
(-1700 4010);
DISPLAY 0.617021 (-1700 4010);
PAINT PINK (-1700 4010);
FORCEPROP 2 LAST CDS_LIB mstr_standard
J 2
(-1700 4000);
DISPLAY 0.787234 (-1700 4000);
PAINT MONO (-1700 4000);
DISPLAY INVISIBLE (-1700 4000);
FORCEPROP 1 LAST BODY_TYPE PLUMBING
J 2
(-1700 3950);
DISPLAY 1.234043 (-1700 3950);
PAINT GREEN (-1700 3950);
DISPLAY INVISIBLE (-1700 3950);
FORCEPROP 1 LAST HDL_TAP TRUE
J 2
(-2025 3875);
DISPLAY 1.234043 (-2025 3875);
PAINT GREEN (-2025 3875);
DISPLAY INVISIBLE (-2025 3875);
FORCEPROP 1 LAST PATH I59
J 2
(-1700 4000);
DISPLAY 0.936170 (-1700 4000);
PAINT GREEN (-1700 4000);
DISPLAY INVISIBLE (-1700 4000);
FORCEADD TAP..6
R 2
(900 4950);
FORCEPROP 3 LASTPIN (850 4950) SIG_NAME M_C_DQS_DN<15>
J 0
(860 4960);
DISPLAY 0.659574 (860 4960);
PAINT MONO (860 4960);
DISPLAY INVISIBLE (860 4960);
FORCEPROP 1 LASTPIN (850 4950) BN 15
J 2
(900 4960);
DISPLAY 0.617021 (900 4960);
PAINT PINK (900 4960);
FORCEPROP 2 LAST CDS_LIB mstr_standard
J 0
(900 4950);
DISPLAY 0.787234 (900 4950);
PAINT MONO (900 4950);
DISPLAY INVISIBLE (900 4950);
FORCEPROP 1 LAST BODY_TYPE PLUMBING
J 2
(900 4900);
DISPLAY 1.234043 (900 4900);
PAINT GREEN (900 4900);
DISPLAY INVISIBLE (900 4900);
FORCEPROP 1 LAST HDL_TAP TRUE
J 2
(575 4825);
DISPLAY 1.234043 (575 4825);
PAINT GREEN (575 4825);
DISPLAY INVISIBLE (575 4825);
FORCEPROP 1 LAST PATH I6
J 2
(900 4950);
DISPLAY 0.936170 (900 4950);
PAINT GREEN (900 4950);
DISPLAY INVISIBLE (900 4950);
FORCEADD TAP..6
R 2
(-1700 3950);
FORCEPROP 3 LASTPIN (-1750 3950) SIG_NAME M_C_DQ<48>
J 0
(-1740 3960);
DISPLAY 0.659574 (-1740 3960);
PAINT MONO (-1740 3960);
DISPLAY INVISIBLE (-1740 3960);
FORCEPROP 1 LASTPIN (-1750 3950) BN 48
J 2
(-1700 3960);
DISPLAY 0.617021 (-1700 3960);
PAINT PINK (-1700 3960);
FORCEPROP 2 LAST CDS_LIB mstr_standard
J 2
(-1700 3950);
DISPLAY 0.787234 (-1700 3950);
PAINT MONO (-1700 3950);
DISPLAY INVISIBLE (-1700 3950);
FORCEPROP 1 LAST BODY_TYPE PLUMBING
J 2
(-1700 3900);
DISPLAY 1.234043 (-1700 3900);
PAINT GREEN (-1700 3900);
DISPLAY INVISIBLE (-1700 3900);
FORCEPROP 1 LAST HDL_TAP TRUE
J 2
(-2025 3825);
DISPLAY 1.234043 (-2025 3825);
PAINT GREEN (-2025 3825);
DISPLAY INVISIBLE (-2025 3825);
FORCEPROP 1 LAST PATH I60
J 2
(-1700 3950);
DISPLAY 0.936170 (-1700 3950);
PAINT GREEN (-1700 3950);
DISPLAY INVISIBLE (-1700 3950);
FORCEADD SCONN288_H44441004..2
(0 4350);
FORCEPROP 1 LAST LOCATION J4G3
J 0
(-400 5450);
DISPLAY 0.617021 (-400 5450);
PAINT AQUA (-400 5450);
FORCEPROP 1 LAST PART_NUMBER H44441-004
J 0
(-400 3250);
DISPLAY 0.617021 (-400 3250);
PAINT BLUE (-400 3250);
FORCEPROP 1 LAST MATERIAL SCONN
J 0
(-400 5400);
DISPLAY 0.617021 (-400 5400);
PAINT SKYBLUE (-400 5400);
FORCEPROP 2 LASTPIN (450 5200) $PN 51
J 0
(460 5210);
DISPLAY 0.617021 (460 5210);
PAINT ORANGE (460 5210);
FORCEPROP 2 LASTPIN (450 5150) $PN 52
J 0
(460 5160);
DISPLAY 0.617021 (460 5160);
PAINT ORANGE (460 5160);
FORCEPROP 2 LASTPIN (450 5100) $PN 132
J 0
(460 5110);
DISPLAY 0.617021 (460 5110);
PAINT ORANGE (460 5110);
FORCEPROP 2 LASTPIN (450 5050) $PN 133
J 0
(460 5060);
DISPLAY 0.617021 (460 5060);
PAINT ORANGE (460 5060);
FORCEPROP 2 LASTPIN (450 5000) $PN 121
J 0
(460 5010);
DISPLAY 0.617021 (460 5010);
PAINT ORANGE (460 5010);
FORCEPROP 2 LASTPIN (450 4950) $PN 122
J 0
(460 4960);
DISPLAY 0.617021 (460 4960);
PAINT ORANGE (460 4960);
FORCEPROP 2 LASTPIN (450 4900) $PN 110
J 0
(460 4910);
DISPLAY 0.617021 (460 4910);
PAINT ORANGE (460 4910);
FORCEPROP 2 LASTPIN (450 4850) $PN 111
J 0
(460 4860);
DISPLAY 0.617021 (460 4860);
PAINT ORANGE (460 4860);
FORCEPROP 2 LASTPIN (450 4800) $PN 99
J 0
(460 4810);
DISPLAY 0.617021 (460 4810);
PAINT ORANGE (460 4810);
FORCEPROP 2 LASTPIN (450 4750) $PN 100
J 0
(460 4760);
DISPLAY 0.617021 (460 4760);
PAINT ORANGE (460 4760);
FORCEPROP 2 LASTPIN (450 4700) $PN 40
J 0
(460 4710);
DISPLAY 0.617021 (460 4710);
PAINT ORANGE (460 4710);
FORCEPROP 2 LASTPIN (450 4650) $PN 41
J 0
(460 4660);
DISPLAY 0.617021 (460 4660);
PAINT ORANGE (460 4660);
FORCEPROP 2 LASTPIN (450 4600) $PN 29
J 0
(460 4610);
DISPLAY 0.617021 (460 4610);
PAINT ORANGE (460 4610);
FORCEPROP 2 LASTPIN (450 4550) $PN 30
J 0
(460 4560);
DISPLAY 0.617021 (460 4560);
PAINT ORANGE (460 4560);
FORCEPROP 2 LASTPIN (450 4500) $PN 18
J 0
(460 4510);
DISPLAY 0.617021 (460 4510);
PAINT ORANGE (460 4510);
FORCEPROP 2 LASTPIN (450 4450) $PN 19
J 0
(460 4460);
DISPLAY 0.617021 (460 4460);
PAINT ORANGE (460 4460);
FORCEPROP 2 LASTPIN (450 4400) $PN 7
J 0
(460 4410);
DISPLAY 0.617021 (460 4410);
PAINT ORANGE (460 4410);
FORCEPROP 2 LASTPIN (450 4350) $PN 8
J 0
(460 4360);
DISPLAY 0.617021 (460 4360);
PAINT ORANGE (460 4360);
FORCEPROP 2 LASTPIN (450 4300) $PN 197
J 0
(460 4310);
DISPLAY 0.617021 (460 4310);
PAINT ORANGE (460 4310);
FORCEPROP 2 LASTPIN (450 4250) $PN 196
J 0
(460 4260);
DISPLAY 0.617021 (460 4260);
PAINT ORANGE (460 4260);
FORCEPROP 2 LASTPIN (450 4200) $PN 278
J 0
(460 4210);
DISPLAY 0.617021 (460 4210);
PAINT ORANGE (460 4210);
FORCEPROP 2 LASTPIN (450 4150) $PN 277
J 0
(460 4160);
DISPLAY 0.617021 (460 4160);
PAINT ORANGE (460 4160);
FORCEPROP 2 LASTPIN (450 4100) $PN 267
J 0
(460 4110);
DISPLAY 0.617021 (460 4110);
PAINT ORANGE (460 4110);
FORCEPROP 2 LASTPIN (450 4050) $PN 266
J 0
(460 4060);
DISPLAY 0.617021 (460 4060);
PAINT ORANGE (460 4060);
FORCEPROP 2 LASTPIN (450 4000) $PN 256
J 0
(460 4010);
DISPLAY 0.617021 (460 4010);
PAINT ORANGE (460 4010);
FORCEPROP 2 LASTPIN (450 3950) $PN 255
J 0
(460 3960);
DISPLAY 0.617021 (460 3960);
PAINT ORANGE (460 3960);
FORCEPROP 2 LASTPIN (450 3900) $PN 245
J 0
(460 3910);
DISPLAY 0.617021 (460 3910);
PAINT ORANGE (460 3910);
FORCEPROP 2 LASTPIN (450 3850) $PN 244
J 0
(460 3860);
DISPLAY 0.617021 (460 3860);
PAINT ORANGE (460 3860);
FORCEPROP 2 LASTPIN (450 3800) $PN 186
J 0
(460 3810);
DISPLAY 0.617021 (460 3810);
PAINT ORANGE (460 3810);
FORCEPROP 2 LASTPIN (450 3750) $PN 185
J 0
(460 3760);
DISPLAY 0.617021 (460 3760);
PAINT ORANGE (460 3760);
FORCEPROP 2 LASTPIN (450 3700) $PN 175
J 0
(460 3710);
DISPLAY 0.617021 (460 3710);
PAINT ORANGE (460 3710);
FORCEPROP 2 LASTPIN (450 3650) $PN 174
J 0
(460 3660);
DISPLAY 0.617021 (460 3660);
PAINT ORANGE (460 3660);
FORCEPROP 2 LASTPIN (450 3600) $PN 164
J 0
(460 3610);
DISPLAY 0.617021 (460 3610);
PAINT ORANGE (460 3610);
FORCEPROP 2 LASTPIN (450 3550) $PN 163
J 0
(460 3560);
DISPLAY 0.617021 (460 3560);
PAINT ORANGE (460 3560);
FORCEPROP 2 LASTPIN (450 3500) $PN 153
J 0
(460 3510);
DISPLAY 0.617021 (460 3510);
PAINT ORANGE (460 3510);
FORCEPROP 2 LASTPIN (450 3450) $PN 152
J 0
(460 3460);
DISPLAY 0.617021 (460 3460);
PAINT ORANGE (460 3460);
FORCEPROP 1 LAST PACK_TYPE PIP
J 0
(-400 5500);
PAINT SKYBLUE (-400 5500);
DISPLAY INVISIBLE (-400 5500);
FORCEPROP 2 LAST BOM_COST MEM
J 0
(0 4350);
PAINT ORANGE (0 4350);
DISPLAY INVISIBLE (0 4350);
FORCEPROP 2 LAST CDS_LIB mstr_sconn
J 0
(0 4350);
PAINT ORANGE (0 4350);
DISPLAY INVISIBLE (0 4350);
FORCEPROP 2 LAST SEC_TYPE PIP
J 0
(-400 5500);
DISPLAY 1.021277 (-400 5500);
PAINT ORANGE (-400 5500);
DISPLAY INVISIBLE (-400 5500);
FORCEPROP 2 LAST SEC 2
J 0
(-400 5500);
DISPLAY 0.680851 (-400 5500);
PAINT MONO (-400 5500);
DISPLAY INVISIBLE (-400 5500);
FORCEPROP 2 LAST CDS_LOCATION J4G3
J 0
(-400 5450);
DISPLAY 0.617021 (-400 5450);
PAINT AQUA (-400 5450);
DISPLAY INVISIBLE (-400 5450);
FORCEPROP 1 LAST PATH I61
J 0
(0 5400);
PAINT GREEN (0 5400);
DISPLAY INVISIBLE (0 5400);
FORCEPROP 2 LAST ROOM DDR4_CH_C
J 0
(-400 5550);
PAINT ORANGE (-400 5550);
DISPLAY INVISIBLE (-400 5550);
FORCEADD TAP..6
R 2
(-1700 3800);
FORCEPROP 3 LASTPIN (-1750 3800) SIG_NAME M_C_DQ<47>
J 0
(-1740 3810);
DISPLAY 0.659574 (-1740 3810);
PAINT MONO (-1740 3810);
DISPLAY INVISIBLE (-1740 3810);
FORCEPROP 1 LASTPIN (-1750 3800) BN 47
J 2
(-1700 3810);
DISPLAY 0.617021 (-1700 3810);
PAINT PINK (-1700 3810);
FORCEPROP 2 LAST CDS_LIB mstr_standard
J 2
(-1700 3800);
DISPLAY 0.787234 (-1700 3800);
PAINT MONO (-1700 3800);
DISPLAY INVISIBLE (-1700 3800);
FORCEPROP 1 LAST BODY_TYPE PLUMBING
J 2
(-1700 3750);
DISPLAY 1.234043 (-1700 3750);
PAINT GREEN (-1700 3750);
DISPLAY INVISIBLE (-1700 3750);
FORCEPROP 1 LAST HDL_TAP TRUE
J 2
(-2025 3675);
DISPLAY 1.234043 (-2025 3675);
PAINT GREEN (-2025 3675);
DISPLAY INVISIBLE (-2025 3675);
FORCEPROP 1 LAST PATH I62
J 2
(-1700 3800);
DISPLAY 0.936170 (-1700 3800);
PAINT GREEN (-1700 3800);
DISPLAY INVISIBLE (-1700 3800);
FORCEADD TAP..6
R 2
(-1700 3850);
FORCEPROP 3 LASTPIN (-1750 3850) SIG_NAME M_C_DQ<46>
J 0
(-1740 3860);
DISPLAY 0.659574 (-1740 3860);
PAINT MONO (-1740 3860);
DISPLAY INVISIBLE (-1740 3860);
FORCEPROP 1 LASTPIN (-1750 3850) BN 46
J 2
(-1700 3860);
DISPLAY 0.617021 (-1700 3860);
PAINT PINK (-1700 3860);
FORCEPROP 2 LAST CDS_LIB mstr_standard
J 2
(-1700 3850);
DISPLAY 0.787234 (-1700 3850);
PAINT MONO (-1700 3850);
DISPLAY INVISIBLE (-1700 3850);
FORCEPROP 1 LAST BODY_TYPE PLUMBING
J 2
(-1700 3800);
DISPLAY 1.234043 (-1700 3800);
PAINT GREEN (-1700 3800);
DISPLAY INVISIBLE (-1700 3800);
FORCEPROP 1 LAST HDL_TAP TRUE
J 2
(-2025 3725);
DISPLAY 1.234043 (-2025 3725);
PAINT GREEN (-2025 3725);
DISPLAY INVISIBLE (-2025 3725);
FORCEPROP 1 LAST PATH I63
J 2
(-1700 3850);
DISPLAY 0.936170 (-1700 3850);
PAINT GREEN (-1700 3850);
DISPLAY INVISIBLE (-1700 3850);
FORCEADD TAP..6
R 2
(-1700 3900);
FORCEPROP 3 LASTPIN (-1750 3900) SIG_NAME M_C_DQ<49>
J 0
(-1740 3910);
DISPLAY 0.659574 (-1740 3910);
PAINT MONO (-1740 3910);
DISPLAY INVISIBLE (-1740 3910);
FORCEPROP 1 LASTPIN (-1750 3900) BN 49
J 2
(-1700 3910);
DISPLAY 0.617021 (-1700 3910);
PAINT PINK (-1700 3910);
FORCEPROP 2 LAST CDS_LIB mstr_standard
J 2
(-1700 3900);
DISPLAY 0.787234 (-1700 3900);
PAINT MONO (-1700 3900);
DISPLAY INVISIBLE (-1700 3900);
FORCEPROP 1 LAST BODY_TYPE PLUMBING
J 2
(-1700 3850);
DISPLAY 1.234043 (-1700 3850);
PAINT GREEN (-1700 3850);
DISPLAY INVISIBLE (-1700 3850);
FORCEPROP 1 LAST HDL_TAP TRUE
J 2
(-2025 3775);
DISPLAY 1.234043 (-2025 3775);
PAINT GREEN (-2025 3775);
DISPLAY INVISIBLE (-2025 3775);
FORCEPROP 1 LAST PATH I64
J 2
(-1700 3900);
DISPLAY 0.936170 (-1700 3900);
PAINT GREEN (-1700 3900);
DISPLAY INVISIBLE (-1700 3900);
FORCEADD TAP..6
R 2
(-1700 3750);
FORCEPROP 3 LASTPIN (-1750 3750) SIG_NAME M_C_DQ<44>
J 0
(-1740 3760);
DISPLAY 0.659574 (-1740 3760);
PAINT MONO (-1740 3760);
DISPLAY INVISIBLE (-1740 3760);
FORCEPROP 1 LASTPIN (-1750 3750) BN 44
J 2
(-1700 3760);
DISPLAY 0.617021 (-1700 3760);
PAINT PINK (-1700 3760);
FORCEPROP 2 LAST CDS_LIB mstr_standard
J 2
(-1700 3750);
DISPLAY 0.787234 (-1700 3750);
PAINT MONO (-1700 3750);
DISPLAY INVISIBLE (-1700 3750);
FORCEPROP 1 LAST BODY_TYPE PLUMBING
J 2
(-1700 3700);
DISPLAY 1.234043 (-1700 3700);
PAINT GREEN (-1700 3700);
DISPLAY INVISIBLE (-1700 3700);
FORCEPROP 1 LAST HDL_TAP TRUE
J 2
(-2025 3625);
DISPLAY 1.234043 (-2025 3625);
PAINT GREEN (-2025 3625);
DISPLAY INVISIBLE (-2025 3625);
FORCEPROP 1 LAST PATH I65
J 2
(-1700 3750);
DISPLAY 0.936170 (-1700 3750);
PAINT GREEN (-1700 3750);
DISPLAY INVISIBLE (-1700 3750);
FORCEADD TAP..6
R 2
(-1700 3700);
FORCEPROP 3 LASTPIN (-1750 3700) SIG_NAME M_C_DQ<45>
J 0
(-1740 3710);
DISPLAY 0.659574 (-1740 3710);
PAINT MONO (-1740 3710);
DISPLAY INVISIBLE (-1740 3710);
FORCEPROP 1 LASTPIN (-1750 3700) BN 45
J 2
(-1700 3710);
DISPLAY 0.617021 (-1700 3710);
PAINT PINK (-1700 3710);
FORCEPROP 2 LAST CDS_LIB mstr_standard
J 2
(-1700 3700);
DISPLAY 0.787234 (-1700 3700);
PAINT MONO (-1700 3700);
DISPLAY INVISIBLE (-1700 3700);
FORCEPROP 1 LAST BODY_TYPE PLUMBING
J 2
(-1700 3650);
DISPLAY 1.234043 (-1700 3650);
PAINT GREEN (-1700 3650);
DISPLAY INVISIBLE (-1700 3650);
FORCEPROP 1 LAST HDL_TAP TRUE
J 2
(-2025 3575);
DISPLAY 1.234043 (-2025 3575);
PAINT GREEN (-2025 3575);
DISPLAY INVISIBLE (-2025 3575);
FORCEPROP 1 LAST PATH I66
J 2
(-1700 3700);
DISPLAY 0.936170 (-1700 3700);
PAINT GREEN (-1700 3700);
DISPLAY INVISIBLE (-1700 3700);
FORCEADD TAP..6
R 2
(-1700 3650);
FORCEPROP 3 LASTPIN (-1750 3650) SIG_NAME M_C_DQ<42>
J 0
(-1740 3660);
DISPLAY 0.659574 (-1740 3660);
PAINT MONO (-1740 3660);
DISPLAY INVISIBLE (-1740 3660);
FORCEPROP 1 LASTPIN (-1750 3650) BN 42
J 2
(-1700 3660);
DISPLAY 0.617021 (-1700 3660);
PAINT PINK (-1700 3660);
FORCEPROP 2 LAST CDS_LIB mstr_standard
J 2
(-1700 3650);
DISPLAY 0.787234 (-1700 3650);
PAINT MONO (-1700 3650);
DISPLAY INVISIBLE (-1700 3650);
FORCEPROP 1 LAST BODY_TYPE PLUMBING
J 2
(-1700 3600);
DISPLAY 1.234043 (-1700 3600);
PAINT GREEN (-1700 3600);
DISPLAY INVISIBLE (-1700 3600);
FORCEPROP 1 LAST HDL_TAP TRUE
J 2
(-2025 3525);
DISPLAY 1.234043 (-2025 3525);
PAINT GREEN (-2025 3525);
DISPLAY INVISIBLE (-2025 3525);
FORCEPROP 1 LAST PATH I67
J 2
(-1700 3650);
DISPLAY 0.936170 (-1700 3650);
PAINT GREEN (-1700 3650);
DISPLAY INVISIBLE (-1700 3650);
FORCEADD TAP..6
R 2
(-1700 3600);
FORCEPROP 3 LASTPIN (-1750 3600) SIG_NAME M_C_DQ<43>
J 0
(-1740 3610);
DISPLAY 0.659574 (-1740 3610);
PAINT MONO (-1740 3610);
DISPLAY INVISIBLE (-1740 3610);
FORCEPROP 1 LASTPIN (-1750 3600) BN 43
J 2
(-1700 3610);
DISPLAY 0.617021 (-1700 3610);
PAINT PINK (-1700 3610);
FORCEPROP 2 LAST CDS_LIB mstr_standard
J 2
(-1700 3600);
DISPLAY 0.787234 (-1700 3600);
PAINT MONO (-1700 3600);
DISPLAY INVISIBLE (-1700 3600);
FORCEPROP 1 LAST BODY_TYPE PLUMBING
J 2
(-1700 3550);
DISPLAY 1.234043 (-1700 3550);
PAINT GREEN (-1700 3550);
DISPLAY INVISIBLE (-1700 3550);
FORCEPROP 1 LAST HDL_TAP TRUE
J 2
(-2025 3475);
DISPLAY 1.234043 (-2025 3475);
PAINT GREEN (-2025 3475);
DISPLAY INVISIBLE (-2025 3475);
FORCEPROP 1 LAST PATH I68
J 2
(-1700 3600);
DISPLAY 0.936170 (-1700 3600);
PAINT GREEN (-1700 3600);
DISPLAY INVISIBLE (-1700 3600);
FORCEADD TAP..6
R 2
(-1700 3550);
FORCEPROP 3 LASTPIN (-1750 3550) SIG_NAME M_C_DQ<40>
J 0
(-1740 3560);
DISPLAY 0.659574 (-1740 3560);
PAINT MONO (-1740 3560);
DISPLAY INVISIBLE (-1740 3560);
FORCEPROP 1 LASTPIN (-1750 3550) BN 40
J 2
(-1700 3560);
DISPLAY 0.617021 (-1700 3560);
PAINT PINK (-1700 3560);
FORCEPROP 2 LAST CDS_LIB mstr_standard
J 2
(-1700 3550);
DISPLAY 0.787234 (-1700 3550);
PAINT MONO (-1700 3550);
DISPLAY INVISIBLE (-1700 3550);
FORCEPROP 1 LAST BODY_TYPE PLUMBING
J 2
(-1700 3500);
DISPLAY 1.234043 (-1700 3500);
PAINT GREEN (-1700 3500);
DISPLAY INVISIBLE (-1700 3500);
FORCEPROP 1 LAST HDL_TAP TRUE
J 2
(-2025 3425);
DISPLAY 1.234043 (-2025 3425);
PAINT GREEN (-2025 3425);
DISPLAY INVISIBLE (-2025 3425);
FORCEPROP 1 LAST PATH I69
J 2
(-1700 3550);
DISPLAY 0.936170 (-1700 3550);
PAINT GREEN (-1700 3550);
DISPLAY INVISIBLE (-1700 3550);
FORCEADD TAP..6
R 2
(900 5050);
FORCEPROP 3 LASTPIN (850 5050) SIG_NAME M_C_DQS_DN<16>
J 0
(860 5060);
DISPLAY 0.659574 (860 5060);
PAINT MONO (860 5060);
DISPLAY INVISIBLE (860 5060);
FORCEPROP 1 LASTPIN (850 5050) BN 16
J 2
(900 5060);
DISPLAY 0.617021 (900 5060);
PAINT PINK (900 5060);
FORCEPROP 2 LAST CDS_LIB mstr_standard
J 0
(900 5050);
DISPLAY 0.787234 (900 5050);
PAINT MONO (900 5050);
DISPLAY INVISIBLE (900 5050);
FORCEPROP 1 LAST BODY_TYPE PLUMBING
J 2
(900 5000);
DISPLAY 1.234043 (900 5000);
PAINT GREEN (900 5000);
DISPLAY INVISIBLE (900 5000);
FORCEPROP 1 LAST HDL_TAP TRUE
J 2
(575 4925);
DISPLAY 1.234043 (575 4925);
PAINT GREEN (575 4925);
DISPLAY INVISIBLE (575 4925);
FORCEPROP 1 LAST PATH I7
J 2
(900 5050);
DISPLAY 0.936170 (900 5050);
PAINT GREEN (900 5050);
DISPLAY INVISIBLE (900 5050);
FORCEADD TAP..6
R 2
(-1700 3450);
FORCEPROP 3 LASTPIN (-1750 3450) SIG_NAME M_C_DQ<38>
J 0
(-1740 3460);
DISPLAY 0.659574 (-1740 3460);
PAINT MONO (-1740 3460);
DISPLAY INVISIBLE (-1740 3460);
FORCEPROP 1 LASTPIN (-1750 3450) BN 38
J 2
(-1700 3460);
DISPLAY 0.617021 (-1700 3460);
PAINT PINK (-1700 3460);
FORCEPROP 2 LAST CDS_LIB mstr_standard
J 2
(-1700 3450);
DISPLAY 0.787234 (-1700 3450);
PAINT MONO (-1700 3450);
DISPLAY INVISIBLE (-1700 3450);
FORCEPROP 1 LAST BODY_TYPE PLUMBING
J 2
(-1700 3400);
DISPLAY 1.234043 (-1700 3400);
PAINT GREEN (-1700 3400);
DISPLAY INVISIBLE (-1700 3400);
FORCEPROP 1 LAST HDL_TAP TRUE
J 2
(-2025 3325);
DISPLAY 1.234043 (-2025 3325);
PAINT GREEN (-2025 3325);
DISPLAY INVISIBLE (-2025 3325);
FORCEPROP 1 LAST PATH I70
J 2
(-1700 3450);
DISPLAY 0.936170 (-1700 3450);
PAINT GREEN (-1700 3450);
DISPLAY INVISIBLE (-1700 3450);
FORCEADD TAP..6
R 2
(-1700 3500);
FORCEPROP 3 LASTPIN (-1750 3500) SIG_NAME M_C_DQ<41>
J 0
(-1740 3510);
DISPLAY 0.659574 (-1740 3510);
PAINT MONO (-1740 3510);
DISPLAY INVISIBLE (-1740 3510);
FORCEPROP 1 LASTPIN (-1750 3500) BN 41
J 2
(-1700 3510);
DISPLAY 0.617021 (-1700 3510);
PAINT PINK (-1700 3510);
FORCEPROP 2 LAST CDS_LIB mstr_standard
J 2
(-1700 3500);
DISPLAY 0.787234 (-1700 3500);
PAINT MONO (-1700 3500);
DISPLAY INVISIBLE (-1700 3500);
FORCEPROP 1 LAST BODY_TYPE PLUMBING
J 2
(-1700 3450);
DISPLAY 1.234043 (-1700 3450);
PAINT GREEN (-1700 3450);
DISPLAY INVISIBLE (-1700 3450);
FORCEPROP 1 LAST HDL_TAP TRUE
J 2
(-2025 3375);
DISPLAY 1.234043 (-2025 3375);
PAINT GREEN (-2025 3375);
DISPLAY INVISIBLE (-2025 3375);
FORCEPROP 1 LAST PATH I71
J 2
(-1700 3500);
DISPLAY 0.936170 (-1700 3500);
PAINT GREEN (-1700 3500);
DISPLAY INVISIBLE (-1700 3500);
FORCEADD TAP..6
R 2
(-1700 3300);
FORCEPROP 3 LASTPIN (-1750 3300) SIG_NAME M_C_DQ<37>
J 0
(-1740 3310);
DISPLAY 0.659574 (-1740 3310);
PAINT MONO (-1740 3310);
DISPLAY INVISIBLE (-1740 3310);
FORCEPROP 1 LASTPIN (-1750 3300) BN 37
J 2
(-1700 3310);
DISPLAY 0.617021 (-1700 3310);
PAINT PINK (-1700 3310);
FORCEPROP 2 LAST CDS_LIB mstr_standard
J 2
(-1700 3300);
DISPLAY 0.787234 (-1700 3300);
PAINT MONO (-1700 3300);
DISPLAY INVISIBLE (-1700 3300);
FORCEPROP 1 LAST BODY_TYPE PLUMBING
J 2
(-1700 3250);
DISPLAY 1.234043 (-1700 3250);
PAINT GREEN (-1700 3250);
DISPLAY INVISIBLE (-1700 3250);
FORCEPROP 1 LAST HDL_TAP TRUE
J 2
(-2025 3175);
DISPLAY 1.234043 (-2025 3175);
PAINT GREEN (-2025 3175);
DISPLAY INVISIBLE (-2025 3175);
FORCEPROP 1 LAST PATH I72
J 2
(-1700 3300);
DISPLAY 0.936170 (-1700 3300);
PAINT GREEN (-1700 3300);
DISPLAY INVISIBLE (-1700 3300);
FORCEADD TAP..6
R 2
(-1700 3350);
FORCEPROP 3 LASTPIN (-1750 3350) SIG_NAME M_C_DQ<36>
J 0
(-1740 3360);
DISPLAY 0.659574 (-1740 3360);
PAINT MONO (-1740 3360);
DISPLAY INVISIBLE (-1740 3360);
FORCEPROP 1 LASTPIN (-1750 3350) BN 36
J 2
(-1700 3360);
DISPLAY 0.617021 (-1700 3360);
PAINT PINK (-1700 3360);
FORCEPROP 2 LAST CDS_LIB mstr_standard
J 2
(-1700 3350);
DISPLAY 0.787234 (-1700 3350);
PAINT MONO (-1700 3350);
DISPLAY INVISIBLE (-1700 3350);
FORCEPROP 1 LAST BODY_TYPE PLUMBING
J 2
(-1700 3300);
DISPLAY 1.234043 (-1700 3300);
PAINT GREEN (-1700 3300);
DISPLAY INVISIBLE (-1700 3300);
FORCEPROP 1 LAST HDL_TAP TRUE
J 2
(-2025 3225);
DISPLAY 1.234043 (-2025 3225);
PAINT GREEN (-2025 3225);
DISPLAY INVISIBLE (-2025 3225);
FORCEPROP 1 LAST PATH I73
J 2
(-1700 3350);
DISPLAY 0.936170 (-1700 3350);
PAINT GREEN (-1700 3350);
DISPLAY INVISIBLE (-1700 3350);
FORCEADD TAP..6
R 2
(-1700 3400);
FORCEPROP 3 LASTPIN (-1750 3400) SIG_NAME M_C_DQ<39>
J 0
(-1740 3410);
DISPLAY 0.659574 (-1740 3410);
PAINT MONO (-1740 3410);
DISPLAY INVISIBLE (-1740 3410);
FORCEPROP 1 LASTPIN (-1750 3400) BN 39
J 2
(-1700 3410);
DISPLAY 0.617021 (-1700 3410);
PAINT PINK (-1700 3410);
FORCEPROP 2 LAST CDS_LIB mstr_standard
J 2
(-1700 3400);
DISPLAY 0.787234 (-1700 3400);
PAINT MONO (-1700 3400);
DISPLAY INVISIBLE (-1700 3400);
FORCEPROP 1 LAST BODY_TYPE PLUMBING
J 2
(-1700 3350);
DISPLAY 1.234043 (-1700 3350);
PAINT GREEN (-1700 3350);
DISPLAY INVISIBLE (-1700 3350);
FORCEPROP 1 LAST HDL_TAP TRUE
J 2
(-2025 3275);
DISPLAY 1.234043 (-2025 3275);
PAINT GREEN (-2025 3275);
DISPLAY INVISIBLE (-2025 3275);
FORCEPROP 1 LAST PATH I74
J 2
(-1700 3400);
DISPLAY 0.936170 (-1700 3400);
PAINT GREEN (-1700 3400);
DISPLAY INVISIBLE (-1700 3400);
FORCEADD TAP..6
R 2
(-1700 3200);
FORCEPROP 3 LASTPIN (-1750 3200) SIG_NAME M_C_DQ<35>
J 0
(-1740 3210);
DISPLAY 0.659574 (-1740 3210);
PAINT MONO (-1740 3210);
DISPLAY INVISIBLE (-1740 3210);
FORCEPROP 1 LASTPIN (-1750 3200) BN 35
J 2
(-1700 3210);
DISPLAY 0.617021 (-1700 3210);
PAINT PINK (-1700 3210);
FORCEPROP 2 LAST CDS_LIB mstr_standard
J 2
(-1700 3200);
DISPLAY 0.787234 (-1700 3200);
PAINT MONO (-1700 3200);
DISPLAY INVISIBLE (-1700 3200);
FORCEPROP 1 LAST BODY_TYPE PLUMBING
J 2
(-1700 3150);
DISPLAY 1.234043 (-1700 3150);
PAINT GREEN (-1700 3150);
DISPLAY INVISIBLE (-1700 3150);
FORCEPROP 1 LAST HDL_TAP TRUE
J 2
(-2025 3075);
DISPLAY 1.234043 (-2025 3075);
PAINT GREEN (-2025 3075);
DISPLAY INVISIBLE (-2025 3075);
FORCEPROP 1 LAST PATH I75
J 2
(-1700 3200);
DISPLAY 0.936170 (-1700 3200);
PAINT GREEN (-1700 3200);
DISPLAY INVISIBLE (-1700 3200);
FORCEADD TAP..6
R 2
(-1700 3250);
FORCEPROP 3 LASTPIN (-1750 3250) SIG_NAME M_C_DQ<34>
J 0
(-1740 3260);
DISPLAY 0.659574 (-1740 3260);
PAINT MONO (-1740 3260);
DISPLAY INVISIBLE (-1740 3260);
FORCEPROP 1 LASTPIN (-1750 3250) BN 34
J 2
(-1700 3260);
DISPLAY 0.617021 (-1700 3260);
PAINT PINK (-1700 3260);
FORCEPROP 2 LAST CDS_LIB mstr_standard
J 2
(-1700 3250);
DISPLAY 0.787234 (-1700 3250);
PAINT MONO (-1700 3250);
DISPLAY INVISIBLE (-1700 3250);
FORCEPROP 1 LAST BODY_TYPE PLUMBING
J 2
(-1700 3200);
DISPLAY 1.234043 (-1700 3200);
PAINT GREEN (-1700 3200);
DISPLAY INVISIBLE (-1700 3200);
FORCEPROP 1 LAST HDL_TAP TRUE
J 2
(-2025 3125);
DISPLAY 1.234043 (-2025 3125);
PAINT GREEN (-2025 3125);
DISPLAY INVISIBLE (-2025 3125);
FORCEPROP 1 LAST PATH I76
J 2
(-1700 3250);
DISPLAY 0.936170 (-1700 3250);
PAINT GREEN (-1700 3250);
DISPLAY INVISIBLE (-1700 3250);
FORCEADD TAP..6
R 2
(-1700 3150);
FORCEPROP 3 LASTPIN (-1750 3150) SIG_NAME M_C_DQ<32>
J 0
(-1740 3160);
DISPLAY 0.659574 (-1740 3160);
PAINT MONO (-1740 3160);
DISPLAY INVISIBLE (-1740 3160);
FORCEPROP 1 LASTPIN (-1750 3150) BN 32
J 2
(-1700 3160);
DISPLAY 0.617021 (-1700 3160);
PAINT PINK (-1700 3160);
FORCEPROP 2 LAST CDS_LIB mstr_standard
J 2
(-1700 3150);
DISPLAY 0.787234 (-1700 3150);
PAINT MONO (-1700 3150);
DISPLAY INVISIBLE (-1700 3150);
FORCEPROP 1 LAST BODY_TYPE PLUMBING
J 2
(-1700 3100);
DISPLAY 1.234043 (-1700 3100);
PAINT GREEN (-1700 3100);
DISPLAY INVISIBLE (-1700 3100);
FORCEPROP 1 LAST HDL_TAP TRUE
J 2
(-2025 3025);
DISPLAY 1.234043 (-2025 3025);
PAINT GREEN (-2025 3025);
DISPLAY INVISIBLE (-2025 3025);
FORCEPROP 1 LAST PATH I77
J 2
(-1700 3150);
DISPLAY 0.936170 (-1700 3150);
PAINT GREEN (-1700 3150);
DISPLAY INVISIBLE (-1700 3150);
FORCEADD TAP..6
R 2
(-1700 3100);
FORCEPROP 3 LASTPIN (-1750 3100) SIG_NAME M_C_DQ<33>
J 0
(-1740 3110);
DISPLAY 0.659574 (-1740 3110);
PAINT MONO (-1740 3110);
DISPLAY INVISIBLE (-1740 3110);
FORCEPROP 1 LASTPIN (-1750 3100) BN 33
J 2
(-1700 3110);
DISPLAY 0.617021 (-1700 3110);
PAINT PINK (-1700 3110);
FORCEPROP 2 LAST CDS_LIB mstr_standard
J 2
(-1700 3100);
DISPLAY 0.787234 (-1700 3100);
PAINT MONO (-1700 3100);
DISPLAY INVISIBLE (-1700 3100);
FORCEPROP 1 LAST BODY_TYPE PLUMBING
J 2
(-1700 3050);
DISPLAY 1.234043 (-1700 3050);
PAINT GREEN (-1700 3050);
DISPLAY INVISIBLE (-1700 3050);
FORCEPROP 1 LAST HDL_TAP TRUE
J 2
(-2025 2975);
DISPLAY 1.234043 (-2025 2975);
PAINT GREEN (-2025 2975);
DISPLAY INVISIBLE (-2025 2975);
FORCEPROP 1 LAST PATH I78
J 2
(-1700 3100);
DISPLAY 0.936170 (-1700 3100);
PAINT GREEN (-1700 3100);
DISPLAY INVISIBLE (-1700 3100);
FORCEADD TAP..6
R 2
(-1700 3050);
FORCEPROP 3 LASTPIN (-1750 3050) SIG_NAME M_C_DQ<30>
J 0
(-1740 3060);
DISPLAY 0.659574 (-1740 3060);
PAINT MONO (-1740 3060);
DISPLAY INVISIBLE (-1740 3060);
FORCEPROP 1 LASTPIN (-1750 3050) BN 30
J 2
(-1700 3060);
DISPLAY 0.617021 (-1700 3060);
PAINT PINK (-1700 3060);
FORCEPROP 2 LAST CDS_LIB mstr_standard
J 2
(-1700 3050);
DISPLAY 0.787234 (-1700 3050);
PAINT MONO (-1700 3050);
DISPLAY INVISIBLE (-1700 3050);
FORCEPROP 1 LAST BODY_TYPE PLUMBING
J 2
(-1700 3000);
DISPLAY 1.234043 (-1700 3000);
PAINT GREEN (-1700 3000);
DISPLAY INVISIBLE (-1700 3000);
FORCEPROP 1 LAST HDL_TAP TRUE
J 2
(-2025 2925);
DISPLAY 1.234043 (-2025 2925);
PAINT GREEN (-2025 2925);
DISPLAY INVISIBLE (-2025 2925);
FORCEPROP 1 LAST PATH I79
J 2
(-1700 3050);
DISPLAY 0.936170 (-1700 3050);
PAINT GREEN (-1700 3050);
DISPLAY INVISIBLE (-1700 3050);
FORCEADD TAP..6
R 2
(900 4850);
FORCEPROP 3 LASTPIN (850 4850) SIG_NAME M_C_DQS_DN<14>
J 0
(860 4860);
DISPLAY 0.659574 (860 4860);
PAINT MONO (860 4860);
DISPLAY INVISIBLE (860 4860);
FORCEPROP 1 LASTPIN (850 4850) BN 14
J 2
(900 4860);
DISPLAY 0.617021 (900 4860);
PAINT PINK (900 4860);
FORCEPROP 2 LAST CDS_LIB mstr_standard
J 0
(900 4850);
DISPLAY 0.787234 (900 4850);
PAINT MONO (900 4850);
DISPLAY INVISIBLE (900 4850);
FORCEPROP 1 LAST BODY_TYPE PLUMBING
J 2
(900 4800);
DISPLAY 1.234043 (900 4800);
PAINT GREEN (900 4800);
DISPLAY INVISIBLE (900 4800);
FORCEPROP 1 LAST HDL_TAP TRUE
J 2
(575 4725);
DISPLAY 1.234043 (575 4725);
PAINT GREEN (575 4725);
DISPLAY INVISIBLE (575 4725);
FORCEPROP 1 LAST PATH I8
J 2
(900 4850);
DISPLAY 0.936170 (900 4850);
PAINT GREEN (900 4850);
DISPLAY INVISIBLE (900 4850);
FORCEADD TAP..6
R 2
(-1700 2900);
FORCEPROP 3 LASTPIN (-1750 2900) SIG_NAME M_C_DQ<29>
J 0
(-1740 2910);
DISPLAY 0.659574 (-1740 2910);
PAINT MONO (-1740 2910);
DISPLAY INVISIBLE (-1740 2910);
FORCEPROP 1 LASTPIN (-1750 2900) BN 29
J 2
(-1700 2910);
DISPLAY 0.617021 (-1700 2910);
PAINT PINK (-1700 2910);
FORCEPROP 2 LAST CDS_LIB mstr_standard
J 2
(-1700 2900);
DISPLAY 0.787234 (-1700 2900);
PAINT MONO (-1700 2900);
DISPLAY INVISIBLE (-1700 2900);
FORCEPROP 1 LAST BODY_TYPE PLUMBING
J 2
(-1700 2850);
DISPLAY 1.234043 (-1700 2850);
PAINT GREEN (-1700 2850);
DISPLAY INVISIBLE (-1700 2850);
FORCEPROP 1 LAST HDL_TAP TRUE
J 2
(-2025 2775);
DISPLAY 1.234043 (-2025 2775);
PAINT GREEN (-2025 2775);
DISPLAY INVISIBLE (-2025 2775);
FORCEPROP 1 LAST PATH I80
J 2
(-1700 2900);
DISPLAY 0.936170 (-1700 2900);
PAINT GREEN (-1700 2900);
DISPLAY INVISIBLE (-1700 2900);
FORCEADD TAP..6
R 2
(-1700 2950);
FORCEPROP 3 LASTPIN (-1750 2950) SIG_NAME M_C_DQ<28>
J 0
(-1740 2960);
DISPLAY 0.659574 (-1740 2960);
PAINT MONO (-1740 2960);
DISPLAY INVISIBLE (-1740 2960);
FORCEPROP 1 LASTPIN (-1750 2950) BN 28
J 2
(-1700 2960);
DISPLAY 0.617021 (-1700 2960);
PAINT PINK (-1700 2960);
FORCEPROP 2 LAST CDS_LIB mstr_standard
J 2
(-1700 2950);
DISPLAY 0.787234 (-1700 2950);
PAINT MONO (-1700 2950);
DISPLAY INVISIBLE (-1700 2950);
FORCEPROP 1 LAST BODY_TYPE PLUMBING
J 2
(-1700 2900);
DISPLAY 1.234043 (-1700 2900);
PAINT GREEN (-1700 2900);
DISPLAY INVISIBLE (-1700 2900);
FORCEPROP 1 LAST HDL_TAP TRUE
J 2
(-2025 2825);
DISPLAY 1.234043 (-2025 2825);
PAINT GREEN (-2025 2825);
DISPLAY INVISIBLE (-2025 2825);
FORCEPROP 1 LAST PATH I81
J 2
(-1700 2950);
DISPLAY 0.936170 (-1700 2950);
PAINT GREEN (-1700 2950);
DISPLAY INVISIBLE (-1700 2950);
FORCEADD TAP..6
R 2
(-1700 3000);
FORCEPROP 3 LASTPIN (-1750 3000) SIG_NAME M_C_DQ<31>
J 0
(-1740 3010);
DISPLAY 0.659574 (-1740 3010);
PAINT MONO (-1740 3010);
DISPLAY INVISIBLE (-1740 3010);
FORCEPROP 1 LASTPIN (-1750 3000) BN 31
J 2
(-1700 3010);
DISPLAY 0.617021 (-1700 3010);
PAINT PINK (-1700 3010);
FORCEPROP 2 LAST CDS_LIB mstr_standard
J 2
(-1700 3000);
DISPLAY 0.787234 (-1700 3000);
PAINT MONO (-1700 3000);
DISPLAY INVISIBLE (-1700 3000);
FORCEPROP 1 LAST BODY_TYPE PLUMBING
J 2
(-1700 2950);
DISPLAY 1.234043 (-1700 2950);
PAINT GREEN (-1700 2950);
DISPLAY INVISIBLE (-1700 2950);
FORCEPROP 1 LAST HDL_TAP TRUE
J 2
(-2025 2875);
DISPLAY 1.234043 (-2025 2875);
PAINT GREEN (-2025 2875);
DISPLAY INVISIBLE (-2025 2875);
FORCEPROP 1 LAST PATH I82
J 2
(-1700 3000);
DISPLAY 0.936170 (-1700 3000);
PAINT GREEN (-1700 3000);
DISPLAY INVISIBLE (-1700 3000);
FORCEADD TAP..6
R 2
(-1700 2850);
FORCEPROP 3 LASTPIN (-1750 2850) SIG_NAME M_C_DQ<26>
J 0
(-1740 2860);
DISPLAY 0.659574 (-1740 2860);
PAINT MONO (-1740 2860);
DISPLAY INVISIBLE (-1740 2860);
FORCEPROP 1 LASTPIN (-1750 2850) BN 26
J 2
(-1700 2860);
DISPLAY 0.617021 (-1700 2860);
PAINT PINK (-1700 2860);
FORCEPROP 2 LAST CDS_LIB mstr_standard
J 2
(-1700 2850);
DISPLAY 0.787234 (-1700 2850);
PAINT MONO (-1700 2850);
DISPLAY INVISIBLE (-1700 2850);
FORCEPROP 1 LAST BODY_TYPE PLUMBING
J 2
(-1700 2800);
DISPLAY 1.234043 (-1700 2800);
PAINT GREEN (-1700 2800);
DISPLAY INVISIBLE (-1700 2800);
FORCEPROP 1 LAST HDL_TAP TRUE
J 2
(-2025 2725);
DISPLAY 1.234043 (-2025 2725);
PAINT GREEN (-2025 2725);
DISPLAY INVISIBLE (-2025 2725);
FORCEPROP 1 LAST PATH I83
J 2
(-1700 2850);
DISPLAY 0.936170 (-1700 2850);
PAINT GREEN (-1700 2850);
DISPLAY INVISIBLE (-1700 2850);
FORCEADD TAP..6
R 2
(-1700 2800);
FORCEPROP 3 LASTPIN (-1750 2800) SIG_NAME M_C_DQ<27>
J 0
(-1740 2810);
DISPLAY 0.659574 (-1740 2810);
PAINT MONO (-1740 2810);
DISPLAY INVISIBLE (-1740 2810);
FORCEPROP 1 LASTPIN (-1750 2800) BN 27
J 2
(-1700 2810);
DISPLAY 0.617021 (-1700 2810);
PAINT PINK (-1700 2810);
FORCEPROP 2 LAST CDS_LIB mstr_standard
J 2
(-1700 2800);
DISPLAY 0.787234 (-1700 2800);
PAINT MONO (-1700 2800);
DISPLAY INVISIBLE (-1700 2800);
FORCEPROP 1 LAST BODY_TYPE PLUMBING
J 2
(-1700 2750);
DISPLAY 1.234043 (-1700 2750);
PAINT GREEN (-1700 2750);
DISPLAY INVISIBLE (-1700 2750);
FORCEPROP 1 LAST HDL_TAP TRUE
J 2
(-2025 2675);
DISPLAY 1.234043 (-2025 2675);
PAINT GREEN (-2025 2675);
DISPLAY INVISIBLE (-2025 2675);
FORCEPROP 1 LAST PATH I84
J 2
(-1700 2800);
DISPLAY 0.936170 (-1700 2800);
PAINT GREEN (-1700 2800);
DISPLAY INVISIBLE (-1700 2800);
FORCEADD TAP..6
R 2
(-1700 2650);
FORCEPROP 3 LASTPIN (-1750 2650) SIG_NAME M_C_DQ<22>
J 0
(-1740 2660);
DISPLAY 0.659574 (-1740 2660);
PAINT MONO (-1740 2660);
DISPLAY INVISIBLE (-1740 2660);
FORCEPROP 1 LASTPIN (-1750 2650) BN 22
J 2
(-1700 2660);
DISPLAY 0.617021 (-1700 2660);
PAINT PINK (-1700 2660);
FORCEPROP 2 LAST CDS_LIB mstr_standard
J 2
(-1700 2650);
DISPLAY 0.787234 (-1700 2650);
PAINT MONO (-1700 2650);
DISPLAY INVISIBLE (-1700 2650);
FORCEPROP 1 LAST BODY_TYPE PLUMBING
J 2
(-1700 2600);
DISPLAY 1.234043 (-1700 2600);
PAINT GREEN (-1700 2600);
DISPLAY INVISIBLE (-1700 2600);
FORCEPROP 1 LAST HDL_TAP TRUE
J 2
(-2025 2525);
DISPLAY 1.234043 (-2025 2525);
PAINT GREEN (-2025 2525);
DISPLAY INVISIBLE (-2025 2525);
FORCEPROP 1 LAST PATH I85
J 2
(-1700 2650);
DISPLAY 0.936170 (-1700 2650);
PAINT GREEN (-1700 2650);
DISPLAY INVISIBLE (-1700 2650);
FORCEADD TAP..6
R 2
(-1700 2750);
FORCEPROP 3 LASTPIN (-1750 2750) SIG_NAME M_C_DQ<24>
J 0
(-1740 2760);
DISPLAY 0.659574 (-1740 2760);
PAINT MONO (-1740 2760);
DISPLAY INVISIBLE (-1740 2760);
FORCEPROP 1 LASTPIN (-1750 2750) BN 24
J 2
(-1700 2760);
DISPLAY 0.617021 (-1700 2760);
PAINT PINK (-1700 2760);
FORCEPROP 2 LAST CDS_LIB mstr_standard
J 2
(-1700 2750);
DISPLAY 0.787234 (-1700 2750);
PAINT MONO (-1700 2750);
DISPLAY INVISIBLE (-1700 2750);
FORCEPROP 1 LAST BODY_TYPE PLUMBING
J 2
(-1700 2700);
DISPLAY 1.234043 (-1700 2700);
PAINT GREEN (-1700 2700);
DISPLAY INVISIBLE (-1700 2700);
FORCEPROP 1 LAST HDL_TAP TRUE
J 2
(-2025 2625);
DISPLAY 1.234043 (-2025 2625);
PAINT GREEN (-2025 2625);
DISPLAY INVISIBLE (-2025 2625);
FORCEPROP 1 LAST PATH I86
J 2
(-1700 2750);
DISPLAY 0.936170 (-1700 2750);
PAINT GREEN (-1700 2750);
DISPLAY INVISIBLE (-1700 2750);
FORCEADD TAP..6
R 2
(-1700 2700);
FORCEPROP 3 LASTPIN (-1750 2700) SIG_NAME M_C_DQ<25>
J 0
(-1740 2710);
DISPLAY 0.659574 (-1740 2710);
PAINT MONO (-1740 2710);
DISPLAY INVISIBLE (-1740 2710);
FORCEPROP 1 LASTPIN (-1750 2700) BN 25
J 2
(-1700 2710);
DISPLAY 0.617021 (-1700 2710);
PAINT PINK (-1700 2710);
FORCEPROP 2 LAST CDS_LIB mstr_standard
J 2
(-1700 2700);
DISPLAY 0.787234 (-1700 2700);
PAINT MONO (-1700 2700);
DISPLAY INVISIBLE (-1700 2700);
FORCEPROP 1 LAST BODY_TYPE PLUMBING
J 2
(-1700 2650);
DISPLAY 1.234043 (-1700 2650);
PAINT GREEN (-1700 2650);
DISPLAY INVISIBLE (-1700 2650);
FORCEPROP 1 LAST HDL_TAP TRUE
J 2
(-2025 2575);
DISPLAY 1.234043 (-2025 2575);
PAINT GREEN (-2025 2575);
DISPLAY INVISIBLE (-2025 2575);
FORCEPROP 1 LAST PATH I87
J 2
(-1700 2700);
DISPLAY 0.936170 (-1700 2700);
PAINT GREEN (-1700 2700);
DISPLAY INVISIBLE (-1700 2700);
FORCEADD TAP..6
R 2
(-1700 2550);
FORCEPROP 3 LASTPIN (-1750 2550) SIG_NAME M_C_DQ<20>
J 0
(-1740 2560);
DISPLAY 0.659574 (-1740 2560);
PAINT MONO (-1740 2560);
DISPLAY INVISIBLE (-1740 2560);
FORCEPROP 1 LASTPIN (-1750 2550) BN 20
J 2
(-1700 2560);
DISPLAY 0.617021 (-1700 2560);
PAINT PINK (-1700 2560);
FORCEPROP 2 LAST CDS_LIB mstr_standard
J 2
(-1700 2550);
DISPLAY 0.787234 (-1700 2550);
PAINT MONO (-1700 2550);
DISPLAY INVISIBLE (-1700 2550);
FORCEPROP 1 LAST BODY_TYPE PLUMBING
J 2
(-1700 2500);
DISPLAY 1.234043 (-1700 2500);
PAINT GREEN (-1700 2500);
DISPLAY INVISIBLE (-1700 2500);
FORCEPROP 1 LAST HDL_TAP TRUE
J 2
(-2025 2425);
DISPLAY 1.234043 (-2025 2425);
PAINT GREEN (-2025 2425);
DISPLAY INVISIBLE (-2025 2425);
FORCEPROP 1 LAST PATH I88
J 2
(-1700 2550);
DISPLAY 0.936170 (-1700 2550);
PAINT GREEN (-1700 2550);
DISPLAY INVISIBLE (-1700 2550);
FORCEADD TAP..6
R 2
(-1700 2600);
FORCEPROP 3 LASTPIN (-1750 2600) SIG_NAME M_C_DQ<23>
J 0
(-1740 2610);
DISPLAY 0.659574 (-1740 2610);
PAINT MONO (-1740 2610);
DISPLAY INVISIBLE (-1740 2610);
FORCEPROP 1 LASTPIN (-1750 2600) BN 23
J 2
(-1700 2610);
DISPLAY 0.617021 (-1700 2610);
PAINT PINK (-1700 2610);
FORCEPROP 2 LAST CDS_LIB mstr_standard
J 2
(-1700 2600);
DISPLAY 0.787234 (-1700 2600);
PAINT MONO (-1700 2600);
DISPLAY INVISIBLE (-1700 2600);
FORCEPROP 1 LAST BODY_TYPE PLUMBING
J 2
(-1700 2550);
DISPLAY 1.234043 (-1700 2550);
PAINT GREEN (-1700 2550);
DISPLAY INVISIBLE (-1700 2550);
FORCEPROP 1 LAST HDL_TAP TRUE
J 2
(-2025 2475);
DISPLAY 1.234043 (-2025 2475);
PAINT GREEN (-2025 2475);
DISPLAY INVISIBLE (-2025 2475);
FORCEPROP 1 LAST PATH I89
J 2
(-1700 2600);
DISPLAY 0.936170 (-1700 2600);
PAINT GREEN (-1700 2600);
DISPLAY INVISIBLE (-1700 2600);
FORCEADD TAP..6
R 2
(700 5000);
FORCEPROP 3 LASTPIN (650 5000) SIG_NAME M_C_DQS_DP<15>
J 0
(660 5010);
DISPLAY 0.659574 (660 5010);
PAINT MONO (660 5010);
DISPLAY INVISIBLE (660 5010);
FORCEPROP 1 LASTPIN (650 5000) BN 15
J 2
(700 5010);
DISPLAY 0.617021 (700 5010);
PAINT PINK (700 5010);
FORCEPROP 2 LAST CDS_LIB mstr_standard
J 0
(700 5000);
DISPLAY 0.787234 (700 5000);
PAINT MONO (700 5000);
DISPLAY INVISIBLE (700 5000);
FORCEPROP 1 LAST BODY_TYPE PLUMBING
J 2
(700 4950);
DISPLAY 1.234043 (700 4950);
PAINT GREEN (700 4950);
DISPLAY INVISIBLE (700 4950);
FORCEPROP 1 LAST HDL_TAP TRUE
J 2
(375 4875);
DISPLAY 1.234043 (375 4875);
PAINT GREEN (375 4875);
DISPLAY INVISIBLE (375 4875);
FORCEPROP 1 LAST PATH I9
J 2
(700 5000);
DISPLAY 0.936170 (700 5000);
PAINT GREEN (700 5000);
DISPLAY INVISIBLE (700 5000);
FORCEADD TAP..6
R 2
(-1700 2500);
FORCEPROP 3 LASTPIN (-1750 2500) SIG_NAME M_C_DQ<21>
J 0
(-1740 2510);
DISPLAY 0.659574 (-1740 2510);
PAINT MONO (-1740 2510);
DISPLAY INVISIBLE (-1740 2510);
FORCEPROP 1 LASTPIN (-1750 2500) BN 21
J 2
(-1700 2510);
DISPLAY 0.617021 (-1700 2510);
PAINT PINK (-1700 2510);
FORCEPROP 2 LAST CDS_LIB mstr_standard
J 2
(-1700 2500);
DISPLAY 0.787234 (-1700 2500);
PAINT MONO (-1700 2500);
DISPLAY INVISIBLE (-1700 2500);
FORCEPROP 1 LAST BODY_TYPE PLUMBING
J 2
(-1700 2450);
DISPLAY 1.234043 (-1700 2450);
PAINT GREEN (-1700 2450);
DISPLAY INVISIBLE (-1700 2450);
FORCEPROP 1 LAST HDL_TAP TRUE
J 2
(-2025 2375);
DISPLAY 1.234043 (-2025 2375);
PAINT GREEN (-2025 2375);
DISPLAY INVISIBLE (-2025 2375);
FORCEPROP 1 LAST PATH I90
J 2
(-1700 2500);
DISPLAY 0.936170 (-1700 2500);
PAINT GREEN (-1700 2500);
DISPLAY INVISIBLE (-1700 2500);
FORCEADD TAP..6
R 2
(-1700 2450);
FORCEPROP 3 LASTPIN (-1750 2450) SIG_NAME M_C_DQ<18>
J 0
(-1740 2460);
DISPLAY 0.659574 (-1740 2460);
PAINT MONO (-1740 2460);
DISPLAY INVISIBLE (-1740 2460);
FORCEPROP 1 LASTPIN (-1750 2450) BN 18
J 2
(-1700 2460);
DISPLAY 0.617021 (-1700 2460);
PAINT PINK (-1700 2460);
FORCEPROP 2 LAST CDS_LIB mstr_standard
J 2
(-1700 2450);
DISPLAY 0.787234 (-1700 2450);
PAINT MONO (-1700 2450);
DISPLAY INVISIBLE (-1700 2450);
FORCEPROP 1 LAST BODY_TYPE PLUMBING
J 2
(-1700 2400);
DISPLAY 1.234043 (-1700 2400);
PAINT GREEN (-1700 2400);
DISPLAY INVISIBLE (-1700 2400);
FORCEPROP 1 LAST HDL_TAP TRUE
J 2
(-2025 2325);
DISPLAY 1.234043 (-2025 2325);
PAINT GREEN (-2025 2325);
DISPLAY INVISIBLE (-2025 2325);
FORCEPROP 1 LAST PATH I91
J 2
(-1700 2450);
DISPLAY 0.936170 (-1700 2450);
PAINT GREEN (-1700 2450);
DISPLAY INVISIBLE (-1700 2450);
FORCEADD TAP..6
R 2
(-1700 2400);
FORCEPROP 3 LASTPIN (-1750 2400) SIG_NAME M_C_DQ<19>
J 0
(-1740 2410);
DISPLAY 0.659574 (-1740 2410);
PAINT MONO (-1740 2410);
DISPLAY INVISIBLE (-1740 2410);
FORCEPROP 1 LASTPIN (-1750 2400) BN 19
J 2
(-1700 2410);
DISPLAY 0.617021 (-1700 2410);
PAINT PINK (-1700 2410);
FORCEPROP 2 LAST CDS_LIB mstr_standard
J 2
(-1700 2400);
DISPLAY 0.787234 (-1700 2400);
PAINT MONO (-1700 2400);
DISPLAY INVISIBLE (-1700 2400);
FORCEPROP 1 LAST BODY_TYPE PLUMBING
J 2
(-1700 2350);
DISPLAY 1.234043 (-1700 2350);
PAINT GREEN (-1700 2350);
DISPLAY INVISIBLE (-1700 2350);
FORCEPROP 1 LAST HDL_TAP TRUE
J 2
(-2025 2275);
DISPLAY 1.234043 (-2025 2275);
PAINT GREEN (-2025 2275);
DISPLAY INVISIBLE (-2025 2275);
FORCEPROP 1 LAST PATH I92
J 2
(-1700 2400);
DISPLAY 0.936170 (-1700 2400);
PAINT GREEN (-1700 2400);
DISPLAY INVISIBLE (-1700 2400);
FORCEADD TAP..6
R 2
(-1700 2300);
FORCEPROP 3 LASTPIN (-1750 2300) SIG_NAME M_C_DQ<17>
J 0
(-1740 2310);
DISPLAY 0.659574 (-1740 2310);
PAINT MONO (-1740 2310);
DISPLAY INVISIBLE (-1740 2310);
FORCEPROP 1 LASTPIN (-1750 2300) BN 17
J 2
(-1700 2310);
DISPLAY 0.617021 (-1700 2310);
PAINT PINK (-1700 2310);
FORCEPROP 2 LAST CDS_LIB mstr_standard
J 2
(-1700 2300);
DISPLAY 0.787234 (-1700 2300);
PAINT MONO (-1700 2300);
DISPLAY INVISIBLE (-1700 2300);
FORCEPROP 1 LAST BODY_TYPE PLUMBING
J 2
(-1700 2250);
DISPLAY 1.234043 (-1700 2250);
PAINT GREEN (-1700 2250);
DISPLAY INVISIBLE (-1700 2250);
FORCEPROP 1 LAST HDL_TAP TRUE
J 2
(-2025 2175);
DISPLAY 1.234043 (-2025 2175);
PAINT GREEN (-2025 2175);
DISPLAY INVISIBLE (-2025 2175);
FORCEPROP 1 LAST PATH I93
J 2
(-1700 2300);
DISPLAY 0.936170 (-1700 2300);
PAINT GREEN (-1700 2300);
DISPLAY INVISIBLE (-1700 2300);
FORCEADD TAP..6
R 2
(-1700 2350);
FORCEPROP 3 LASTPIN (-1750 2350) SIG_NAME M_C_DQ<16>
J 0
(-1740 2360);
DISPLAY 0.659574 (-1740 2360);
PAINT MONO (-1740 2360);
DISPLAY INVISIBLE (-1740 2360);
FORCEPROP 1 LASTPIN (-1750 2350) BN 16
J 2
(-1700 2360);
DISPLAY 0.617021 (-1700 2360);
PAINT PINK (-1700 2360);
FORCEPROP 2 LAST CDS_LIB mstr_standard
J 2
(-1700 2350);
DISPLAY 0.787234 (-1700 2350);
PAINT MONO (-1700 2350);
DISPLAY INVISIBLE (-1700 2350);
FORCEPROP 1 LAST BODY_TYPE PLUMBING
J 2
(-1700 2300);
DISPLAY 1.234043 (-1700 2300);
PAINT GREEN (-1700 2300);
DISPLAY INVISIBLE (-1700 2300);
FORCEPROP 1 LAST HDL_TAP TRUE
J 2
(-2025 2225);
DISPLAY 1.234043 (-2025 2225);
PAINT GREEN (-2025 2225);
DISPLAY INVISIBLE (-2025 2225);
FORCEPROP 1 LAST PATH I94
J 2
(-1700 2350);
DISPLAY 0.936170 (-1700 2350);
PAINT GREEN (-1700 2350);
DISPLAY INVISIBLE (-1700 2350);
FORCEADD TAP..6
R 2
(-1700 2150);
FORCEPROP 3 LASTPIN (-1750 2150) SIG_NAME M_C_DQ<12>
J 0
(-1740 2160);
DISPLAY 0.659574 (-1740 2160);
PAINT MONO (-1740 2160);
DISPLAY INVISIBLE (-1740 2160);
FORCEPROP 1 LASTPIN (-1750 2150) BN 12
J 2
(-1700 2160);
DISPLAY 0.617021 (-1700 2160);
PAINT PINK (-1700 2160);
FORCEPROP 2 LAST CDS_LIB mstr_standard
J 2
(-1700 2150);
DISPLAY 0.787234 (-1700 2150);
PAINT MONO (-1700 2150);
DISPLAY INVISIBLE (-1700 2150);
FORCEPROP 1 LAST BODY_TYPE PLUMBING
J 2
(-1700 2100);
DISPLAY 1.234043 (-1700 2100);
PAINT GREEN (-1700 2100);
DISPLAY INVISIBLE (-1700 2100);
FORCEPROP 1 LAST HDL_TAP TRUE
J 2
(-2025 2025);
DISPLAY 1.234043 (-2025 2025);
PAINT GREEN (-2025 2025);
DISPLAY INVISIBLE (-2025 2025);
FORCEPROP 1 LAST PATH I95
J 2
(-1700 2150);
DISPLAY 0.936170 (-1700 2150);
PAINT GREEN (-1700 2150);
DISPLAY INVISIBLE (-1700 2150);
FORCEADD TAP..6
R 2
(-1700 2200);
FORCEPROP 3 LASTPIN (-1750 2200) SIG_NAME M_C_DQ<15>
J 0
(-1740 2210);
DISPLAY 0.659574 (-1740 2210);
PAINT MONO (-1740 2210);
DISPLAY INVISIBLE (-1740 2210);
FORCEPROP 1 LASTPIN (-1750 2200) BN 15
J 2
(-1700 2210);
DISPLAY 0.617021 (-1700 2210);
PAINT PINK (-1700 2210);
FORCEPROP 2 LAST CDS_LIB mstr_standard
J 2
(-1700 2200);
DISPLAY 0.787234 (-1700 2200);
PAINT MONO (-1700 2200);
DISPLAY INVISIBLE (-1700 2200);
FORCEPROP 1 LAST BODY_TYPE PLUMBING
J 2
(-1700 2150);
DISPLAY 1.234043 (-1700 2150);
PAINT GREEN (-1700 2150);
DISPLAY INVISIBLE (-1700 2150);
FORCEPROP 1 LAST HDL_TAP TRUE
J 2
(-2025 2075);
DISPLAY 1.234043 (-2025 2075);
PAINT GREEN (-2025 2075);
DISPLAY INVISIBLE (-2025 2075);
FORCEPROP 1 LAST PATH I96
J 2
(-1700 2200);
DISPLAY 0.936170 (-1700 2200);
PAINT GREEN (-1700 2200);
DISPLAY INVISIBLE (-1700 2200);
FORCEADD TAP..6
R 2
(-1700 2250);
FORCEPROP 3 LASTPIN (-1750 2250) SIG_NAME M_C_DQ<14>
J 0
(-1740 2260);
DISPLAY 0.659574 (-1740 2260);
PAINT MONO (-1740 2260);
DISPLAY INVISIBLE (-1740 2260);
FORCEPROP 1 LASTPIN (-1750 2250) BN 14
J 2
(-1700 2260);
DISPLAY 0.617021 (-1700 2260);
PAINT PINK (-1700 2260);
FORCEPROP 2 LAST CDS_LIB mstr_standard
J 2
(-1700 2250);
DISPLAY 0.787234 (-1700 2250);
PAINT MONO (-1700 2250);
DISPLAY INVISIBLE (-1700 2250);
FORCEPROP 1 LAST BODY_TYPE PLUMBING
J 2
(-1700 2200);
DISPLAY 1.234043 (-1700 2200);
PAINT GREEN (-1700 2200);
DISPLAY INVISIBLE (-1700 2200);
FORCEPROP 1 LAST HDL_TAP TRUE
J 2
(-2025 2125);
DISPLAY 1.234043 (-2025 2125);
PAINT GREEN (-2025 2125);
DISPLAY INVISIBLE (-2025 2125);
FORCEPROP 1 LAST PATH I97
J 2
(-1700 2250);
DISPLAY 0.936170 (-1700 2250);
PAINT GREEN (-1700 2250);
DISPLAY INVISIBLE (-1700 2250);
FORCEADD TAP..6
R 2
(-1700 2050);
FORCEPROP 3 LASTPIN (-1750 2050) SIG_NAME M_C_DQ<10>
J 0
(-1740 2060);
DISPLAY 0.659574 (-1740 2060);
PAINT MONO (-1740 2060);
DISPLAY INVISIBLE (-1740 2060);
FORCEPROP 1 LASTPIN (-1750 2050) BN 10
J 2
(-1700 2060);
DISPLAY 0.617021 (-1700 2060);
PAINT PINK (-1700 2060);
FORCEPROP 2 LAST CDS_LIB mstr_standard
J 2
(-1700 2050);
DISPLAY 0.787234 (-1700 2050);
PAINT MONO (-1700 2050);
DISPLAY INVISIBLE (-1700 2050);
FORCEPROP 1 LAST BODY_TYPE PLUMBING
J 2
(-1700 2000);
DISPLAY 1.234043 (-1700 2000);
PAINT GREEN (-1700 2000);
DISPLAY INVISIBLE (-1700 2000);
FORCEPROP 1 LAST HDL_TAP TRUE
J 2
(-2025 1925);
DISPLAY 1.234043 (-2025 1925);
PAINT GREEN (-2025 1925);
DISPLAY INVISIBLE (-2025 1925);
FORCEPROP 1 LAST PATH I98
J 2
(-1700 2050);
DISPLAY 0.936170 (-1700 2050);
PAINT GREEN (-1700 2050);
DISPLAY INVISIBLE (-1700 2050);
FORCEADD TAP..6
R 2
(-1700 2100);
FORCEPROP 3 LASTPIN (-1750 2100) SIG_NAME M_C_DQ<13>
J 0
(-1740 2110);
DISPLAY 0.659574 (-1740 2110);
PAINT MONO (-1740 2110);
DISPLAY INVISIBLE (-1740 2110);
FORCEPROP 1 LASTPIN (-1750 2100) BN 13
J 2
(-1700 2110);
DISPLAY 0.617021 (-1700 2110);
PAINT PINK (-1700 2110);
FORCEPROP 2 LAST CDS_LIB mstr_standard
J 2
(-1700 2100);
DISPLAY 0.787234 (-1700 2100);
PAINT MONO (-1700 2100);
DISPLAY INVISIBLE (-1700 2100);
FORCEPROP 1 LAST BODY_TYPE PLUMBING
J 2
(-1700 2050);
DISPLAY 1.234043 (-1700 2050);
PAINT GREEN (-1700 2050);
DISPLAY INVISIBLE (-1700 2050);
FORCEPROP 1 LAST HDL_TAP TRUE
J 2
(-2025 1975);
DISPLAY 1.234043 (-2025 1975);
PAINT GREEN (-2025 1975);
DISPLAY INVISIBLE (-2025 1975);
FORCEPROP 1 LAST PATH I99
J 2
(-1700 2100);
DISPLAY 0.936170 (-1700 2100);
PAINT GREEN (-1700 2100);
DISPLAY INVISIBLE (-1700 2100);
FORCEADD BOM_NOTE..1
(-4975 5275);
FORCEPROP 0 LAST L1 STUFF FOR SKU A & B
J 0
(-5125 5175);
DISPLAY 1.063830 (-5125 5175);
PAINT WHITE (-5125 5175);
FORCEPROP 2 LAST CDS_LIB mstr_symbols
J 0
(-4975 5275);
PAINT ORANGE (-4975 5275);
DISPLAY INVISIBLE (-4975 5275);
FORCEPROP 2 LAST BOM_COST SB
J 0
(-5125 5250);
DISPLAY 1.361702 (-5125 5250);
PAINT ORANGE (-5125 5250);
DISPLAY INVISIBLE (-5125 5250);
FORCEPROP 1 LAST COMMENT_BODY TRUE
J 0
(-4950 5375);
DISPLAY 1.319149 (-4950 5375);
PAINT ORANGE (-4950 5375);
DISPLAY INVISIBLE (-4950 5375);
FORCEPROP 2 LAST ROOM SB_HEADERS
J 0
(-5125 5250);
DISPLAY 1.361702 (-5125 5250);
PAINT ORANGE (-5125 5250);
DISPLAY INVISIBLE (-5125 5250);
FORCEADD INTEL_CORP_BPAGE..1
(2650 500);
FORCEPROP 1 LAST CDS_CON_LAST_MODIFIED Tue Dec 01 11:51:28 2015
J 0
(1225 825);
DISPLAY 0.787234 (1225 825);
PAINT ORANGE (1225 825);
DISPLAY INVISIBLE (1225 825);
FORCEPROP 1 LAST CUSTOM_TXT_CDS <CURRENT_DESIGN_SHEET> OF <TOTAL_DESIGN_SHEETS>
J 0
(2150 525);
PAINT GREEN (2150 525);
FORCEPROP 1 LAST CUSTOM_TXT_CDS <CON_LAST_MODIFIED>
J 0
(725 850);
PAINT GREEN (725 850);
FORCEPROP 2 LAST CUSTOM_TXT_CDS <XR_PAGE_TITLE>
J 0
(-5240 5750);
DISPLAY 0.638298 (-5240 5750);
PAINT PINK (-5240 5750);
DISPLAY INVISIBLE (-5240 5750);
FORCEPROP 1 LAST SCH_ADDRESS3 Santa Clara, CA 95052-8119
J 0
(-1325 525);
DISPLAY 0.617021 (-1325 525);
PAINT GREEN (-1325 525);
FORCEPROP 1 LAST SCH_ADDRESS2 P.O. BOX 58119
J 0
(-1325 575);
DISPLAY 0.617021 (-1325 575);
PAINT GREEN (-1325 575);
FORCEPROP 1 LAST SCH_ADDRESS1 2200 Mission College Blvd.
J 0
(-1325 625);
DISPLAY 0.617021 (-1325 625);
PAINT GREEN (-1325 625);
FORCEPROP 1 LAST SCH_TITLE CPU0 DDR4 CH C DIMM0
J 0
(-5300 550);
DISPLAY 1.212766 (-5300 550);
PAINT WHITE (-5300 550);
FORCEPROP 1 LAST SCH_NUMBER H4694802
J 0
(1350 650);
DISPLAY 1.212766 (1350 650);
PAINT YELLOW (1350 650);
FORCEPROP 1 LAST SCH_DEPT BESD
J 1
(-1800 600);
DISPLAY 1.212766 (-1800 600);
PAINT YELLOW (-1800 600);
FORCEPROP 1 LAST SCH_REV 2.420
J 0
(2400 650);
DISPLAY 0.978723 (2400 650);
PAINT YELLOW (2400 650);
FORCEPROP 2 LAST PAGE_BORDER TRUE
J 0
(-5240 5750);
DISPLAY 0.680851 (-5240 5750);
PAINT PINK (-5240 5750);
DISPLAY INVISIBLE (-5240 5750);
FORCEPROP 2 LAST CDS_LIB mstr_symbols
J 0
(2650 500);
DISPLAY 0.787234 (2650 500);
PAINT MONO (2650 500);
DISPLAY INVISIBLE (2650 500);
FORCEPROP 1 LAST COMMENT_BODY TRUE
J 0
(2660 510);
DISPLAY 0.382979 (2660 510);
PAINT GREEN (2660 510);
DISPLAY INVISIBLE (2660 510);
FORCEPROP 2 LAST CDS_XR_PAGE_TITLE CR-47 : @BASEBOARD_FAB2_LIB.BASEBOARD_FAB2(SCH_1):PAGE47
J 0
(-5240 5750);
DISPLAY 0.638298 (-5240 5750);
PAINT PINK (-5240 5750);
DISPLAY INVISIBLE (-5240 5750);
WIRE 17 -1 (950 5075)(950 5175);
WIRE 17 -1 (950 4975)(950 5075);
WIRE 17 -1 (950 5175)(950 5200);
WIRE 17 -1 (1550 5200)(950 5200);
FORCEPROP 2 LAST SIG_NAME M_C_DQS_DN<17:0>
J 0
(1000 5210);
DISPLAY 0.617021 (1000 5210);
PAINT ORANGE (1000 5210);
WIRE 17 -1 (750 5125)(750 5225);
WIRE 17 -1 (750 5025)(750 5125);
WIRE 17 -1 (750 5225)(750 5250);
WIRE 17 -1 (1550 5250)(750 5250);
FORCEPROP 2 LAST SIG_NAME M_C_DQS_DP<17:0>
J 0
(1000 5260);
DISPLAY 0.617021 (1000 5260);
PAINT ORANGE (1000 5260);
WIRE 17 -1 (950 4475)(950 4575);
WIRE 17 -1 (950 4375)(950 4475);
WIRE 17 -1 (950 4575)(950 4675);
WIRE 17 -1 (950 4675)(950 4775);
WIRE 17 -1 (950 4275)(950 4375);
WIRE 17 -1 (950 4175)(950 4275);
WIRE 17 -1 (950 4775)(950 4875);
WIRE 17 -1 (950 4875)(950 4975);
WIRE 17 -1 (950 4075)(950 4175);
WIRE 17 -1 (950 3975)(950 4075);
WIRE 17 -1 (950 3875)(950 3975);
WIRE 17 -1 (950 3775)(950 3875);
WIRE 17 -1 (750 4525)(750 4625);
WIRE 17 -1 (750 4425)(750 4525);
WIRE 17 -1 (750 4625)(750 4725);
WIRE 17 -1 (750 4725)(750 4825);
WIRE 17 -1 (750 4325)(750 4425);
WIRE 17 -1 (750 4225)(750 4325);
WIRE 17 -1 (750 4825)(750 4925);
WIRE 17 -1 (750 4925)(750 5025);
WIRE 17 -1 (750 4125)(750 4225);
WIRE 17 -1 (750 4025)(750 4125);
WIRE 17 -1 (750 3925)(750 4025);
WIRE 17 -1 (750 3825)(750 3925);
WIRE 17 -1 (750 3725)(750 3825);
WIRE 17 -1 (750 3625)(750 3725);
WIRE 17 -1 (750 3525)(750 3625);
WIRE 17 -1 (950 3675)(950 3775);
WIRE 17 -1 (950 3575)(950 3675);
WIRE 17 -1 (950 3475)(950 3575);
WIRE 17 -1 (-1650 4625)(-1650 4675);
WIRE 17 -1 (-1650 4575)(-1650 4625);
WIRE 17 -1 (-1650 4675)(-1650 4700);
WIRE 17 -1 (-1200 4700)(-1650 4700);
FORCEPROP 2 LAST SIG_NAME M_C_DQ<63:0>
J 0
(-1610 4710);
DISPLAY 0.617021 (-1610 4710);
PAINT ORANGE (-1610 4710);
WIRE 17 -1 (-1650 4525)(-1650 4575);
WIRE 17 -1 (-1650 4475)(-1650 4525);
WIRE 17 -1 (-1650 4425)(-1650 4475);
WIRE 17 -1 (-1650 4375)(-1650 4425);
WIRE 17 -1 (-1650 4325)(-1650 4375);
WIRE 17 -1 (-1650 4275)(-1650 4325);
WIRE 17 -1 (-1650 4225)(-1650 4275);
WIRE 17 -1 (-1650 4175)(-1650 4225);
WIRE 17 -1 (-1650 4125)(-1650 4175);
WIRE 17 -1 (-1650 4075)(-1650 4125);
WIRE 17 -1 (-1650 4025)(-1650 4075);
WIRE 17 -1 (-1650 3975)(-1650 4025);
WIRE 17 -1 (-1650 3925)(-1650 3975);
WIRE 17 -1 (-1650 3875)(-1650 3925);
WIRE 17 -1 (-1650 3825)(-1650 3875);
WIRE 17 -1 (-1650 3775)(-1650 3825);
WIRE 17 -1 (-1650 3725)(-1650 3775);
WIRE 17 -1 (-1650 3675)(-1650 3725);
WIRE 17 -1 (-1650 3625)(-1650 3675);
WIRE 17 -1 (-1650 3575)(-1650 3625);
WIRE 17 -1 (-3250 4375)(-3250 4425);
WIRE 17 -1 (-3250 4325)(-3250 4375);
WIRE 17 -1 (-3250 4425)(-3250 4475);
WIRE 17 -1 (-3250 4475)(-3250 4525);
WIRE 17 -1 (-3250 4275)(-3250 4325);
WIRE 17 -1 (-3250 4225)(-3250 4275);
WIRE 17 -1 (-3250 4525)(-3250 4575);
WIRE 17 -1 (-3250 4575)(-3250 4625);
WIRE 17 -1 (-3250 4175)(-3250 4225);
WIRE 17 -1 (-3250 4125)(-3250 4175);
WIRE 17 -1 (-3250 4625)(-3250 4675);
WIRE 17 -1 (-3250 4675)(-3250 4700);
WIRE 17 -1 (-3250 4075)(-3250 4125);
WIRE 17 -1 (-3250 4025)(-3250 4075);
WIRE 17 -1 (-3750 4700)(-3250 4700);
FORCEPROP 2 LAST SIG_NAME M_C_MA<17:0>
J 0
(-3725 4710);
DISPLAY 0.617021 (-3725 4710);
PAINT ORANGE (-3725 4710);
WIRE 17 -1 (-3250 3975)(-3250 4025);
WIRE 17 -1 (-3250 3925)(-3250 3975);
WIRE 17 -1 (-3250 3875)(-3250 3925);
WIRE 17 -1 (-3250 3825)(-3250 3875);
WIRE 17 -1 (-1650 3525)(-1650 3575);
WIRE 17 -1 (-1650 3475)(-1650 3525);
WIRE 17 -1 (-1650 3425)(-1650 3475);
WIRE 17 -1 (-1650 3375)(-1650 3425);
WIRE 17 -1 (-1650 3325)(-1650 3375);
WIRE 17 -1 (-1650 3275)(-1650 3325);
WIRE 17 -1 (-1650 3225)(-1650 3275);
WIRE 17 -1 (-1650 3175)(-1650 3225);
WIRE 17 -1 (-1650 3125)(-1650 3175);
WIRE 17 -1 (-1650 3075)(-1650 3125);
WIRE 17 -1 (-1650 3025)(-1650 3075);
WIRE 17 -1 (-1650 2975)(-1650 3025);
WIRE 17 -1 (-1650 2925)(-1650 2975);
WIRE 17 -1 (-1650 2875)(-1650 2925);
WIRE 17 -1 (-1650 2825)(-1650 2875);
WIRE 17 -1 (-1650 2775)(-1650 2825);
WIRE 17 -1 (-1650 2725)(-1650 2775);
WIRE 17 -1 (-1650 2675)(-1650 2725);
WIRE 17 -1 (-1650 2625)(-1650 2675);
WIRE 17 -1 (-1650 2575)(-1650 2625);
WIRE 17 -1 (-1650 2525)(-1650 2575);
WIRE 17 -1 (-1650 2475)(-1650 2525);
WIRE 17 -1 (-1650 2425)(-1650 2475);
WIRE 17 -1 (-1650 2375)(-1650 2425);
WIRE 17 -1 (-1650 2325)(-1650 2375);
WIRE 17 -1 (-1650 2275)(-1650 2325);
WIRE 17 -1 (-1650 2225)(-1650 2275);
WIRE 17 -1 (-1650 2175)(-1650 2225);
WIRE 17 -1 (-1650 2125)(-1650 2175);
WIRE 17 -1 (-1650 2075)(-1650 2125);
WIRE 17 -1 (-1650 2025)(-1650 2075);
WIRE 17 -1 (-1650 1975)(-1650 2025);
WIRE 17 -1 (-1650 1925)(-1650 1975);
WIRE 17 -1 (-1650 1875)(-1650 1925);
WIRE 17 -1 (-1650 1825)(-1650 1875);
WIRE 17 -1 (-1650 1775)(-1650 1825);
WIRE 17 -1 (-1650 1725)(-1650 1775);
WIRE 17 -1 (-1650 1675)(-1650 1725);
WIRE 17 -1 (-1650 1625)(-1650 1675);
WIRE 17 -1 (-1650 1575)(-1650 1625);
WIRE 17 -1 (-1650 1525)(-1650 1575);
WIRE 17 -1 (-3800 3425)(-3800 3500);
WIRE 17 -1 (-3800 3325)(-3800 3425);
WIRE 17 -1 (-3800 3500)(-4250 3500);
FORCEPROP 2 LAST SIG_NAME M_C_CLK_DN<3:0>
J 0
(-4225 3510);
DISPLAY 0.617021 (-4225 3510);
PAINT ORANGE (-4225 3510);
WIRE 17 -1 (-3650 3475)(-3650 3375);
WIRE 17 -1 (-3650 3550)(-3650 3475);
WIRE 17 -1 (-3650 3550)(-4250 3550);
FORCEPROP 2 LAST SIG_NAME M_C_CLK_DP<3:0>
J 0
(-4225 3560);
DISPLAY 0.617021 (-4225 3560);
PAINT ORANGE (-4225 3560);
WIRE 17 -1 (-3250 3750)(-3250 3725);
WIRE 17 -1 (-3250 3750)(-3750 3750);
FORCEPROP 2 LAST SIG_NAME M_C_BA<1:0>
J 0
(-3725 3760);
DISPLAY 0.617021 (-3725 3760);
PAINT ORANGE (-3725 3760);
WIRE 17 -1 (-3250 3125)(-3250 3175);
WIRE 17 -1 (-3250 3075)(-3250 3125);
WIRE 17 -1 (-3250 3175)(-3250 3200);
WIRE 17 -1 (-3250 3200)(-3750 3200);
FORCEPROP 2 LAST SIG_NAME M_C_CS_N<7:0>
J 0
(-3725 3210);
DISPLAY 0.617021 (-3725 3210);
PAINT ORANGE (-3725 3210);
WIRE 17 -1 (-3250 3025)(-3250 3075);
WIRE 17 -1 (-3250 2525)(-3250 2575);
WIRE 17 -1 (-3250 2475)(-3250 2525);
WIRE 17 -1 (-3250 2575)(-3250 2625);
WIRE 17 -1 (-3250 2625)(-3250 2650);
WIRE 17 -1 (-3250 2425)(-3250 2475);
WIRE 17 -1 (-3250 2375)(-3250 2425);
WIRE 17 -1 (-3250 2650)(-3750 2650);
FORCEPROP 2 LAST SIG_NAME M_C_ECC<7:0>
J 0
(-3700 2660);
DISPLAY 0.617021 (-3700 2660);
PAINT ORANGE (-3700 2660);
WIRE 17 -1 (-3250 2325)(-3250 2375);
WIRE 17 -1 (-3250 2275)(-3250 2325);
WIRE 17 -1 (-3250 2925)(-3250 2950);
WIRE 17 -1 (-3250 2875)(-3250 2925);
WIRE 17 -1 (-3250 2950)(-3750 2950);
FORCEPROP 2 LAST SIG_NAME M_C_CKE<3:0>
J 0
(-3700 2960);
DISPLAY 0.617021 (-3700 2960);
PAINT ORANGE (-3700 2960);
WIRE 17 -1 (-3250 3575)(-3250 3625);
WIRE 17 -1 (-3250 3625)(-3250 3650);
WIRE 17 -1 (-3250 3650)(-3750 3650);
FORCEPROP 2 LAST SIG_NAME M_C_BG<1:0>
J 0
(-3725 3660);
DISPLAY 0.617021 (-3725 3660);
PAINT ORANGE (-3725 3660);
WIRE 17 -1 (-3250 3675)(-3250 3725);
WIRE 17 -1 (-3250 2725)(-3250 2775);
WIRE 17 -1 (-3250 2775)(-3250 2850);
WIRE 17 -1 (-3250 2850)(-3750 2850);
FORCEPROP 2 LAST SIG_NAME M_C_ODT<3:0>
J 0
(-3700 2860);
DISPLAY 0.617021 (-3700 2860);
PAINT ORANGE (-3700 2860);
WIRE 16 -1 (-700 2600)(-500 2600);
WIRE 16 -1 (-700 2550)(-700 2600);
WIRE 16 -1 (-700 2550)(-500 2550);
WIRE 16 -1 (-850 2550)(-700 2550);
WIRE 16 -1 (-850 2650)(-850 2550);
WIRE 16 -1 (-700 1200)(-500 1200);
WIRE 16 -1 (-700 1250)(-700 1200);
WIRE 16 -1 (-700 1250)(-500 1250);
WIRE 16 -1 (-700 1300)(-700 1250);
WIRE 16 -1 (-700 1300)(-500 1300);
WIRE 16 -1 (-700 1350)(-700 1300);
WIRE 16 -1 (-700 1350)(-500 1350);
WIRE 16 -1 (-700 1400)(-700 1350);
WIRE 16 -1 (-700 1400)(-500 1400);
WIRE 16 -1 (-700 1450)(-700 1400);
WIRE 16 -1 (-700 1450)(-500 1450);
WIRE 16 -1 (-700 1500)(-700 1450);
WIRE 16 -1 (-700 1500)(-500 1500);
WIRE 16 -1 (-700 1550)(-700 1500);
WIRE 16 -1 (-700 1550)(-500 1550);
WIRE 16 -1 (-700 1600)(-700 1550);
WIRE 16 -1 (-700 1600)(-500 1600);
WIRE 16 -1 (-700 1650)(-700 1600);
WIRE 16 -1 (-700 1650)(-500 1650);
WIRE 16 -1 (-700 1700)(-700 1650);
WIRE 16 -1 (-700 1700)(-500 1700);
WIRE 16 -1 (-700 1750)(-700 1700);
WIRE 16 -1 (-700 1750)(-500 1750);
WIRE 16 -1 (-700 1800)(-700 1750);
WIRE 16 -1 (-700 1800)(-500 1800);
WIRE 16 -1 (-700 1850)(-700 1800);
WIRE 16 -1 (-700 1850)(-500 1850);
WIRE 16 -1 (-700 1900)(-700 1850);
WIRE 16 -1 (-700 1900)(-500 1900);
WIRE 16 -1 (-700 1950)(-700 1900);
WIRE 16 -1 (-700 1950)(-500 1950);
WIRE 16 -1 (-700 2000)(-700 1950);
WIRE 16 -1 (-700 2050)(-700 2000);
WIRE 16 -1 (-700 2000)(-500 2000);
WIRE 16 -1 (-700 2050)(-500 2050);
WIRE 16 -1 (-700 2100)(-700 2050);
WIRE 16 -1 (-700 2100)(-500 2100);
WIRE 16 -1 (-700 2150)(-700 2100);
WIRE 16 -1 (-700 2150)(-500 2150);
WIRE 16 -1 (-700 2200)(-700 2150);
WIRE 16 -1 (-700 2200)(-500 2200);
WIRE 16 -1 (-700 2250)(-700 2200);
WIRE 16 -1 (-700 2250)(-500 2250);
WIRE 16 -1 (-700 2300)(-700 2250);
WIRE 16 -1 (-700 2300)(-500 2300);
WIRE 16 -1 (-700 2350)(-700 2300);
WIRE 16 -1 (-700 2350)(-500 2350);
WIRE 16 -1 (-700 2400)(-700 2350);
WIRE 16 -1 (-700 2400)(-500 2400);
WIRE 16 -1 (-700 2450)(-700 2400);
WIRE 16 -1 (-700 2450)(-500 2450);
WIRE 16 -1 (-700 2450)(-1150 2450);
WIRE 16 -1 (-1150 2550)(-1150 2450);
WIRE 16 -1 (2500 3800)(2500 3750);
WIRE 16 -1 (2500 3800)(2300 3800);
WIRE 16 -1 (2500 3700)(2500 3750);
WIRE 16 -1 (2500 3750)(2300 3750);
WIRE 16 -1 (2500 3650)(2500 3700);
WIRE 16 -1 (2500 3700)(2300 3700);
WIRE 16 -1 (2500 3600)(2500 3650);
WIRE 16 -1 (2500 3650)(2300 3650);
WIRE 16 -1 (2500 3600)(2300 3600);
WIRE 16 -1 (2500 3550)(2500 3600);
WIRE 16 -1 (2500 3500)(2500 3550);
WIRE 16 -1 (2500 3550)(2300 3550);
WIRE 16 -1 (2500 3450)(2500 3500);
WIRE 16 -1 (2500 3500)(2300 3500);
WIRE 16 -1 (2500 3400)(2500 3450);
WIRE 16 -1 (2500 3450)(2300 3450);
WIRE 16 -1 (2500 3350)(2500 3400);
WIRE 16 -1 (2500 3400)(2300 3400);
WIRE 16 -1 (2500 3300)(2500 3350);
WIRE 16 -1 (2500 3350)(2300 3350);
WIRE 16 -1 (2500 3250)(2500 3300);
WIRE 16 -1 (2500 3300)(2300 3300);
WIRE 16 -1 (2500 3200)(2500 3250);
WIRE 16 -1 (2500 3250)(2300 3250);
WIRE 16 -1 (2500 3150)(2500 3200);
WIRE 16 -1 (2500 3200)(2300 3200);
WIRE 16 -1 (2500 3100)(2500 3150);
WIRE 16 -1 (2500 3150)(2300 3150);
WIRE 16 -1 (2500 3100)(2300 3100);
WIRE 16 -1 (2500 3050)(2500 3100);
WIRE 16 -1 (2500 3000)(2500 3050);
WIRE 16 -1 (2500 3050)(2300 3050);
WIRE 16 -1 (2500 2950)(2500 3000);
WIRE 16 -1 (2500 3000)(2300 3000);
WIRE 16 -1 (2500 2900)(2500 2950);
WIRE 16 -1 (2500 2950)(2300 2950);
WIRE 16 -1 (2500 2850)(2500 2900);
WIRE 16 -1 (2500 2900)(2300 2900);
WIRE 16 -1 (2500 2800)(2500 2850);
WIRE 16 -1 (2500 2850)(2300 2850);
WIRE 16 -1 (2500 2750)(2500 2800);
WIRE 16 -1 (2500 2800)(2300 2800);
WIRE 16 -1 (2500 2700)(2500 2750);
WIRE 16 -1 (2500 2750)(2300 2750);
WIRE 16 -1 (2500 2650)(2500 2700);
WIRE 16 -1 (2500 2700)(2300 2700);
WIRE 16 -1 (2500 2600)(2500 2650);
WIRE 16 -1 (2500 2650)(2300 2650);
WIRE 16 -1 (2500 2600)(2300 2600);
WIRE 16 -1 (2500 2550)(2500 2600);
WIRE 16 -1 (2500 2500)(2500 2550);
WIRE 16 -1 (2500 2550)(2300 2550);
WIRE 16 -1 (2500 2450)(2500 2500);
WIRE 16 -1 (2500 2500)(2300 2500);
WIRE 16 -1 (2500 2400)(2500 2450);
WIRE 16 -1 (2500 2450)(2300 2450);
WIRE 16 -1 (2500 2350)(2500 2400);
WIRE 16 -1 (2500 2400)(2300 2400);
WIRE 16 -1 (2500 2300)(2500 2350);
WIRE 16 -1 (2500 2350)(2300 2350);
WIRE 16 -1 (2500 2250)(2500 2300);
WIRE 16 -1 (2500 2300)(2300 2300);
WIRE 16 -1 (2500 2200)(2500 2250);
WIRE 16 -1 (2500 2250)(2300 2250);
WIRE 16 -1 (2500 2150)(2500 2200);
WIRE 16 -1 (2500 2200)(2300 2200);
WIRE 16 -1 (2500 2100)(2500 2150);
WIRE 16 -1 (2500 2150)(2300 2150);
WIRE 16 -1 (2500 2050)(2500 2100);
WIRE 16 -1 (2500 2100)(2300 2100);
WIRE 16 -1 (2500 2050)(2300 2050);
WIRE 16 -1 (2500 2000)(2500 2050);
WIRE 16 -1 (2500 1950)(2500 2000);
WIRE 16 -1 (2500 2000)(2300 2000);
WIRE 16 -1 (2500 1900)(2500 1950);
WIRE 16 -1 (2500 1950)(2300 1950);
WIRE 16 -1 (2500 1850)(2500 1900);
WIRE 16 -1 (2500 1900)(2300 1900);
WIRE 16 -1 (2500 1800)(2500 1850);
WIRE 16 -1 (2500 1850)(2300 1850);
WIRE 16 -1 (2500 1750)(2500 1800);
WIRE 16 -1 (2500 1800)(2300 1800);
WIRE 16 -1 (2500 1700)(2500 1750);
WIRE 16 -1 (2500 1750)(2300 1750);
WIRE 16 -1 (2500 1650)(2500 1700);
WIRE 16 -1 (2500 1700)(2300 1700);
WIRE 16 -1 (2500 1600)(2500 1650);
WIRE 16 -1 (2500 1650)(2300 1650);
WIRE 16 -1 (2500 1550)(2500 1600);
WIRE 16 -1 (2500 1600)(2300 1600);
WIRE 16 -1 (2500 1550)(2300 1550);
WIRE 16 -1 (2500 1500)(2500 1550);
WIRE 16 -1 (2500 1500)(2500 1400);
WIRE 16 -1 (2500 1500)(2300 1500);
WIRE 16 -1 (-2950 1700)(-3300 1700);
WIRE 16 -1 (-3300 1750)(-3300 1700);
WIRE 16 -1 (-2950 1750)(-3300 1750);
WIRE 16 -1 (-3300 1750)(-4950 1750);
WIRE 16 -1 (-4950 1750)(-4950 1700);
WIRE 16 -1 (-4650 1200)(-4650 1100);
WIRE 16 -1 (-700 2700)(-500 2700);
WIRE 16 -1 (-700 2750)(-700 2700);
WIRE 16 -1 (-700 2750)(-500 2750);
WIRE 16 -1 (-700 2800)(-700 2750);
WIRE 16 -1 (-700 2800)(-500 2800);
WIRE 16 -1 (-700 2850)(-700 2800);
WIRE 16 -1 (-700 2850)(-500 2850);
WIRE 16 -1 (-700 2900)(-700 2850);
WIRE 16 -1 (-700 2900)(-500 2900);
WIRE 16 -1 (-700 3000)(-700 2900);
WIRE 16 -1 (-2950 1800)(-3300 1800);
WIRE 16 -1 (-3300 1800)(-3300 1850);
WIRE 16 -1 (-3300 1850)(-2950 1850);
WIRE 16 -1 (-4950 1850)(-3300 1850);
WIRE 16 -1 (-4950 1950)(-4950 1850);
WIRE 16 -1 (500 2850)(700 2850);
WIRE 16 -1 (700 2850)(700 2900);
WIRE 16 -1 (500 2900)(700 2900);
WIRE 16 -1 (700 2900)(700 3075);
WIRE 16 -1 (1100 3800)(1300 3800);
WIRE 16 -1 (1100 3800)(1100 3750);
WIRE 16 -1 (1100 3750)(1300 3750);
WIRE 16 -1 (1100 3700)(1100 3750);
WIRE 16 -1 (1100 3700)(1300 3700);
WIRE 16 -1 (1100 3650)(1100 3700);
WIRE 16 -1 (1100 3650)(1300 3650);
WIRE 16 -1 (1100 3600)(1100 3650);
WIRE 16 -1 (1100 3600)(1300 3600);
WIRE 16 -1 (1100 3550)(1100 3600);
WIRE 16 -1 (1100 3550)(1300 3550);
WIRE 16 -1 (1100 3500)(1100 3550);
WIRE 16 -1 (1100 3500)(1300 3500);
WIRE 16 -1 (1100 3450)(1100 3500);
WIRE 16 -1 (1100 3450)(1300 3450);
WIRE 16 -1 (1100 3400)(1100 3450);
WIRE 16 -1 (1100 3400)(1300 3400);
WIRE 16 -1 (1100 3350)(1100 3400);
WIRE 16 -1 (1100 3350)(1300 3350);
WIRE 16 -1 (1100 3300)(1100 3350);
WIRE 16 -1 (1100 3300)(1300 3300);
WIRE 16 -1 (1100 3250)(1100 3300);
WIRE 16 -1 (1100 3250)(1300 3250);
WIRE 16 -1 (1100 3200)(1100 3250);
WIRE 16 -1 (1100 3200)(1300 3200);
WIRE 16 -1 (1100 3150)(1100 3200);
WIRE 16 -1 (1100 3150)(1300 3150);
WIRE 16 -1 (1100 3100)(1100 3150);
WIRE 16 -1 (1100 3100)(1300 3100);
WIRE 16 -1 (1100 3050)(1100 3100);
WIRE 16 -1 (1100 3050)(1300 3050);
WIRE 16 -1 (1100 3000)(1100 3050);
WIRE 16 -1 (1100 3000)(1300 3000);
WIRE 16 -1 (1100 2950)(1100 3000);
WIRE 16 -1 (1100 2950)(1300 2950);
WIRE 16 -1 (1100 2900)(1100 2950);
WIRE 16 -1 (1100 2900)(1300 2900);
WIRE 16 -1 (1100 2850)(1100 2900);
WIRE 16 -1 (1100 2850)(1300 2850);
WIRE 16 -1 (1100 2800)(1100 2850);
WIRE 16 -1 (1100 2800)(1300 2800);
WIRE 16 -1 (1100 2750)(1100 2800);
WIRE 16 -1 (1100 2750)(1300 2750);
WIRE 16 -1 (1100 2700)(1100 2750);
WIRE 16 -1 (1100 2700)(1300 2700);
WIRE 16 -1 (1100 2650)(1100 2700);
WIRE 16 -1 (1100 2650)(1300 2650);
WIRE 16 -1 (1100 2600)(1100 2650);
WIRE 16 -1 (1100 2600)(1300 2600);
WIRE 16 -1 (1100 2550)(1100 2600);
WIRE 16 -1 (1100 2550)(1300 2550);
WIRE 16 -1 (1100 2500)(1100 2550);
WIRE 16 -1 (1100 2500)(1300 2500);
WIRE 16 -1 (1100 2450)(1100 2500);
WIRE 16 -1 (1100 2450)(1300 2450);
WIRE 16 -1 (1100 2400)(1100 2450);
WIRE 16 -1 (1100 2400)(1300 2400);
WIRE 16 -1 (1100 2350)(1100 2400);
WIRE 16 -1 (1100 2350)(1300 2350);
WIRE 16 -1 (1100 2300)(1100 2350);
WIRE 16 -1 (1100 2300)(1300 2300);
WIRE 16 -1 (1100 2250)(1100 2300);
WIRE 16 -1 (1100 2250)(1300 2250);
WIRE 16 -1 (1100 2200)(1100 2250);
WIRE 16 -1 (1100 2200)(1300 2200);
WIRE 16 -1 (1100 2150)(1100 2200);
WIRE 16 -1 (1100 2150)(1300 2150);
WIRE 16 -1 (1100 2100)(1100 2150);
WIRE 16 -1 (1100 2100)(1300 2100);
WIRE 16 -1 (1100 2050)(1100 2100);
WIRE 16 -1 (1100 2050)(1300 2050);
WIRE 16 -1 (1100 2000)(1100 2050);
WIRE 16 -1 (1100 2000)(1300 2000);
WIRE 16 -1 (1100 1950)(1100 2000);
WIRE 16 -1 (1100 1950)(1300 1950);
WIRE 16 -1 (1100 1900)(1100 1950);
WIRE 16 -1 (1100 1900)(1300 1900);
WIRE 16 -1 (1100 1850)(1100 1900);
WIRE 16 -1 (1100 1850)(1300 1850);
WIRE 16 -1 (1100 1800)(1100 1850);
WIRE 16 -1 (1100 1800)(1300 1800);
WIRE 16 -1 (1100 1750)(1100 1800);
WIRE 16 -1 (1100 1750)(1300 1750);
WIRE 16 -1 (1100 1700)(1100 1750);
WIRE 16 -1 (1100 1700)(1300 1700);
WIRE 16 -1 (1100 1650)(1100 1700);
WIRE 16 -1 (1100 1650)(1300 1650);
WIRE 16 -1 (1100 1600)(1100 1650);
WIRE 16 -1 (1100 1600)(1300 1600);
WIRE 16 -1 (1100 1550)(1100 1600);
WIRE 16 -1 (1100 1550)(1300 1550);
WIRE 16 -1 (1100 1500)(1100 1550);
WIRE 16 -1 (1100 1500)(1300 1500);
WIRE 16 -1 (1100 1500)(1100 1400);
WIRE 16 -1 (-4650 1400)(-4650 1500);
WIRE 16 -1 (-2950 1500)(-4650 1500);
FORCEPROP 2 LAST SIG_NAME M_C_VREF
J 0
(-3700 1510);
DISPLAY 0.617021 (-3700 1510);
PAINT ORANGE (-3700 1510);
WIRE 16 -1 (-4750 1500)(-4650 1500);
WIRE 16 -1 (-3800 1350)(-2950 1350);
FORCEPROP 2 LAST SIG_NAME TP_CH_C_DIMM_C0_RFU_1
J 0
(-3750 1360);
DISPLAY 0.617021 (-3750 1360);
PAINT ORANGE (-3750 1360);
FORCEPROP 2 LASTPROP $XRERR UNIQUE?
J 0
(-4040 1350);
DISPLAY 0.638298 (-4040 1350);
PAINT MONO (-4040 1350);
DISPLAY INVISIBLE (-4040 1350);
WIRE 16 -1 (-3800 1300)(-2950 1300);
FORCEPROP 2 LAST SIG_NAME TP_CH_C_DIMM_C0_RFU_0
J 0
(-3750 1310);
DISPLAY 0.617021 (-3750 1310);
PAINT ORANGE (-3750 1310);
FORCEPROP 2 LASTPROP $XRERR UNIQUE?
J 0
(-4040 1300);
DISPLAY 0.638298 (-4040 1300);
PAINT MONO (-4040 1300);
DISPLAY INVISIBLE (-4040 1300);
WIRE 16 -1 (-3800 1400)(-2950 1400);
FORCEPROP 2 LAST SIG_NAME TP_CH_C_DIMM_C0_RFU_2
J 0
(-3750 1410);
DISPLAY 0.617021 (-3750 1410);
PAINT ORANGE (-3750 1410);
FORCEPROP 2 LASTPROP $XRERR UNIQUE?
J 0
(-4040 1400);
DISPLAY 0.638298 (-4040 1400);
PAINT MONO (-4040 1400);
DISPLAY INVISIBLE (-4040 1400);
WIRE 16 -1 (-2950 2000)(-3975 2000);
FORCEPROP 2 LAST SIG_NAME M_C_ALERT_N
J 0
(-3925 2010);
DISPLAY 0.617021 (-3925 2010);
PAINT ORANGE (-3925 2010);
WIRE 16 -1 (-2950 1950)(-3950 1950);
FORCEPROP 2 LAST SIG_NAME M_C_ACT_N
J 0
(-3900 1960);
DISPLAY 0.617021 (-3900 1960);
PAINT ORANGE (-3900 1960);
WIRE 16 -1 (-3750 1600)(-2950 1600);
FORCEPROP 2 LAST SIG_NAME SMB_DDR_ABC_VPP_SCL
J 0
(-3710 1610);
DISPLAY 0.617021 (-3710 1610);
PAINT ORANGE (-3710 1610);
WIRE 16 -1 (-2950 1650)(-3750 1650);
WIRE 16 -1 (-3800 1200)(-2950 1200);
FORCEPROP 2 LAST SIG_NAME FM_ADR_COMPLETE_ABC_N
J 0
(-3750 1210);
DISPLAY 0.617021 (-3750 1210);
PAINT ORANGE (-3750 1210);
WIRE 16 -1 (-3400 2050)(-2950 2050);
WIRE 16 -1 (-3400 2050)(-3400 2300);
WIRE 16 -1 (-3400 2300)(-4125 2300);
FORCEPROP 2 LAST SIG_NAME FM_DIMM_EVENT_COD_N
J 0
(-4105 2319);
DISPLAY 0.617021 (-4105 2319);
PAINT ORANGE (-4105 2319);
WIRE 16 -1 (-2950 2100)(-3350 2100);
WIRE 16 -1 (-3350 2100)(-3350 2550);
WIRE 16 -1 (-3350 2550)(-3750 2550);
FORCEPROP 2 LAST SIG_NAME M_ABC_RST_N
J 0
(-3700 2560);
DISPLAY 0.617021 (-3700 2560);
PAINT ORANGE (-3700 2560);
WIRE 16 -1 (-2950 2150)(-3300 2150);
WIRE 16 -1 (-3300 2150)(-3300 2600);
WIRE 16 -1 (-3300 2600)(-3750 2600);
FORCEPROP 2 LAST SIG_NAME M_C_PAR
J 0
(-3700 2610);
DISPLAY 0.617021 (-3700 2610);
PAINT ORANGE (-3700 2610);
WIRE 16 -1 (-3150 3200)(-2950 3200);
WIRE 16 -1 (-3150 3250)(-3150 3200);
WIRE 16 -1 (-3150 3250)(-3750 3250);
FORCEPROP 2 LAST SIG_NAME M_C_C<2>
J 0
(-3725 3260);
DISPLAY 0.617021 (-3725 3260);
PAINT ORANGE (-3725 3260);
WIRE 16 -1 (-2950 3000)(-3150 3000);
WIRE 16 -1 (-2950 2850)(-3150 2850);
WIRE 16 -1 (-2950 2750)(-3150 2750);
WIRE 16 -1 (-2950 2700)(-3150 2700);
WIRE 16 -1 (-2950 2600)(-3150 2600);
WIRE 16 -1 (-2950 3900)(-3150 3900);
WIRE 16 -1 (-2950 3650)(-3150 3650);
WIRE 16 -1 (-2950 3600)(-3150 3600);
WIRE 16 -1 (-2950 3550)(-3150 3550);
WIRE 16 -1 (-2950 2900)(-3150 2900);
WIRE 16 -1 (-2950 2250)(-3150 2250);
WIRE 16 -1 (-2950 2300)(-3150 2300);
WIRE 16 -1 (-2950 2350)(-3150 2350);
WIRE 16 -1 (-2950 2400)(-3150 2400);
WIRE 16 -1 (-2950 2450)(-3150 2450);
WIRE 16 -1 (-2950 2500)(-3150 2500);
WIRE 16 -1 (-2950 2550)(-3150 2550);
WIRE 16 -1 (-2950 4050)(-3150 4050);
WIRE 16 -1 (-2950 4000)(-3150 4000);
WIRE 16 -1 (-2950 3950)(-3150 3950);
WIRE 16 -1 (-2950 3850)(-3150 3850);
WIRE 16 -1 (-2950 3800)(-3150 3800);
WIRE 16 -1 (-2950 3050)(-3150 3050);
WIRE 16 -1 (-2950 3100)(-3150 3100);
WIRE 16 -1 (-2950 3150)(-3150 3150);
WIRE 16 -1 (-2950 3700)(-3150 3700);
WIRE 16 -1 (-2950 3450)(-3550 3450);
WIRE 16 -1 (-2950 3300)(-3700 3300);
WIRE 16 -1 (-2950 3350)(-3550 3350);
WIRE 16 -1 (-2950 3400)(-3700 3400);
WIRE 16 -1 (-1750 1500)(-1950 1500);
WIRE 16 -1 (-1750 1750)(-1950 1750);
WIRE 16 -1 (-1750 1700)(-1950 1700);
WIRE 16 -1 (-1750 1650)(-1950 1650);
WIRE 16 -1 (-1750 1600)(-1950 1600);
WIRE 16 -1 (-1750 1550)(-1950 1550);
WIRE 16 -1 (-1750 1800)(-1950 1800);
WIRE 16 -1 (-1750 1850)(-1950 1850);
WIRE 16 -1 (-1750 1900)(-1950 1900);
WIRE 16 -1 (-1750 1950)(-1950 1950);
WIRE 16 -1 (-1750 2000)(-1950 2000);
WIRE 16 -1 (-1750 2350)(-1950 2350);
WIRE 16 -1 (-1750 2250)(-1950 2250);
WIRE 16 -1 (-1750 2050)(-1950 2050);
WIRE 16 -1 (-1750 2100)(-1950 2100);
WIRE 16 -1 (-1750 2150)(-1950 2150);
WIRE 16 -1 (-1750 2200)(-1950 2200);
WIRE 16 -1 (-1750 2300)(-1950 2300);
WIRE 16 -1 (-1750 2400)(-1950 2400);
WIRE 16 -1 (-1750 2450)(-1950 2450);
WIRE 16 -1 (-1750 2500)(-1950 2500);
WIRE 16 -1 (-1750 2550)(-1950 2550);
WIRE 16 -1 (-1750 2800)(-1950 2800);
WIRE 16 -1 (-1750 2850)(-1950 2850);
WIRE 16 -1 (-1750 2600)(-1950 2600);
WIRE 16 -1 (-1750 2650)(-1950 2650);
WIRE 16 -1 (-1750 2700)(-1950 2700);
WIRE 16 -1 (-1750 2750)(-1950 2750);
WIRE 16 -1 (-1750 3000)(-1950 3000);
WIRE 16 -1 (-1750 3050)(-1950 3050);
WIRE 16 -1 (-1750 2900)(-1950 2900);
WIRE 16 -1 (-1750 2950)(-1950 2950);
WIRE 16 -1 (-1750 3400)(-1950 3400);
WIRE 16 -1 (-1750 3300)(-1950 3300);
WIRE 16 -1 (-1750 3250)(-1950 3250);
WIRE 16 -1 (-1750 3100)(-1950 3100);
WIRE 16 -1 (-1750 3150)(-1950 3150);
WIRE 16 -1 (-1750 3200)(-1950 3200);
WIRE 16 -1 (-1750 3350)(-1950 3350);
WIRE 16 -1 (-1750 3450)(-1950 3450);
WIRE 16 -1 (-1750 3500)(-1950 3500);
WIRE 16 -1 (-1750 3550)(-1950 3550);
WIRE 16 -1 (-1750 3850)(-1950 3850);
WIRE 16 -1 (-1750 3900)(-1950 3900);
WIRE 16 -1 (-1750 3950)(-1950 3950);
WIRE 16 -1 (-1750 4000)(-1950 4000);
WIRE 16 -1 (-1750 4050)(-1950 4050);
WIRE 16 -1 (-1750 3600)(-1950 3600);
WIRE 16 -1 (-1750 3650)(-1950 3650);
WIRE 16 -1 (-1750 3700)(-1950 3700);
WIRE 16 -1 (-1750 3750)(-1950 3750);
WIRE 16 -1 (-1750 3800)(-1950 3800);
WIRE 16 -1 (-2950 4600)(-3150 4600);
WIRE 16 -1 (-2950 4550)(-3150 4550);
WIRE 16 -1 (-2950 4500)(-3150 4500);
WIRE 16 -1 (-2950 4350)(-3150 4350);
WIRE 16 -1 (-2950 4300)(-3150 4300);
WIRE 16 -1 (-2950 4250)(-3150 4250);
WIRE 16 -1 (-2950 4200)(-3150 4200);
WIRE 16 -1 (-2950 4150)(-3150 4150);
WIRE 16 -1 (-2950 4100)(-3150 4100);
WIRE 16 -1 (-2950 4650)(-3150 4650);
WIRE 16 -1 (-2950 4450)(-3150 4450);
WIRE 16 -1 (-2950 4400)(-3150 4400);
WIRE 16 -1 (-1750 4600)(-1950 4600);
WIRE 16 -1 (-1750 4550)(-1950 4550);
WIRE 16 -1 (-1750 4100)(-1950 4100);
WIRE 16 -1 (-1750 4150)(-1950 4150);
WIRE 16 -1 (-1750 4200)(-1950 4200);
WIRE 16 -1 (-1750 4400)(-1950 4400);
WIRE 16 -1 (-1750 4350)(-1950 4350);
WIRE 16 -1 (-1750 4250)(-1950 4250);
WIRE 16 -1 (-1750 4300)(-1950 4300);
WIRE 16 -1 (-1750 4450)(-1950 4450);
WIRE 16 -1 (-1750 4500)(-1950 4500);
WIRE 16 -1 (-1750 4650)(-1950 4650);
WIRE 16 -1 (850 4050)(450 4050);
WIRE 16 -1 (650 4000)(450 4000);
WIRE 16 -1 (850 3950)(450 3950);
WIRE 16 -1 (650 3900)(450 3900);
WIRE 16 -1 (850 3850)(450 3850);
WIRE 16 -1 (650 3800)(450 3800);
WIRE 16 -1 (850 3750)(450 3750);
WIRE 16 -1 (650 3700)(450 3700);
WIRE 16 -1 (850 3650)(450 3650);
WIRE 16 -1 (650 3600)(450 3600);
WIRE 16 -1 (850 3550)(450 3550);
WIRE 16 -1 (650 3500)(450 3500);
WIRE 16 -1 (850 3450)(450 3450);
WIRE 16 -1 (650 4400)(450 4400);
WIRE 16 -1 (850 4350)(450 4350);
WIRE 16 -1 (650 4300)(450 4300);
WIRE 16 -1 (850 4250)(450 4250);
WIRE 16 -1 (650 4200)(450 4200);
WIRE 16 -1 (850 4150)(450 4150);
WIRE 16 -1 (650 4100)(450 4100);
WIRE 16 -1 (650 5100)(450 5100);
WIRE 16 -1 (850 5050)(450 5050);
WIRE 16 -1 (650 5000)(450 5000);
WIRE 16 -1 (850 4950)(450 4950);
WIRE 16 -1 (650 4900)(450 4900);
WIRE 16 -1 (850 4850)(450 4850);
WIRE 16 -1 (650 4800)(450 4800);
WIRE 16 -1 (850 4750)(450 4750);
WIRE 16 -1 (650 4700)(450 4700);
WIRE 16 -1 (850 4650)(450 4650);
WIRE 16 -1 (650 4600)(450 4600);
WIRE 16 -1 (850 4550)(450 4550);
WIRE 16 -1 (650 4500)(450 4500);
WIRE 16 -1 (850 4450)(450 4450);
WIRE 16 -1 (650 5200)(450 5200);
WIRE 16 -1 (850 5150)(450 5150);
DOT 1 (1100 2500);
DOT 1 (2500 3500);
DOT 1 (2500 3550);
DOT 1 (700 2900);
DOT 1 (-700 2450);
DOT 1 (-700 1250);
DOT 1 (-700 2550);
DOT 1 (-700 1300);
DOT 1 (-700 1450);
DOT 1 (-700 1400);
DOT 1 (-700 1350);
DOT 1 (-700 1500);
DOT 1 (-700 1550);
DOT 1 (-700 1600);
DOT 1 (-700 1650);
DOT 1 (-700 1700);
DOT 1 (-700 1750);
DOT 1 (-700 1800);
DOT 1 (-700 1900);
DOT 1 (-700 2050);
DOT 1 (-700 2100);
DOT 1 (-700 2200);
DOT 1 (-700 2150);
DOT 1 (-700 2350);
DOT 1 (-700 2250);
DOT 1 (-700 2300);
DOT 1 (-700 2400);
DOT 1 (-700 2850);
DOT 1 (-700 2800);
DOT 1 (-700 2900);
DOT 1 (1100 1500);
DOT 1 (1100 1550);
DOT 1 (1100 1600);
DOT 1 (1100 1650);
DOT 1 (1100 1700);
DOT 1 (1100 1750);
DOT 1 (1100 1800);
DOT 1 (1100 1850);
DOT 1 (1100 1900);
DOT 1 (1100 1950);
DOT 1 (1100 2000);
DOT 1 (1100 2050);
DOT 1 (1100 2150);
DOT 1 (1100 2200);
DOT 1 (1100 2250);
DOT 1 (1100 2300);
DOT 1 (1100 2350);
DOT 1 (1100 2400);
DOT 1 (1100 2450);
DOT 1 (1100 2550);
DOT 1 (1100 2600);
DOT 1 (1100 2650);
DOT 1 (1100 2700);
DOT 1 (1100 2850);
DOT 1 (1100 2900);
DOT 1 (1100 2950);
DOT 1 (1100 3000);
DOT 1 (1100 3050);
DOT 1 (1100 3100);
DOT 1 (1100 3150);
DOT 1 (1100 3200);
DOT 1 (1100 3250);
DOT 1 (1100 3300);
DOT 1 (1100 3350);
DOT 1 (1100 3400);
DOT 1 (1100 3450);
DOT 1 (1100 3500);
DOT 1 (1100 3550);
DOT 1 (1100 3600);
DOT 1 (1100 3650);
DOT 1 (1100 3700);
DOT 1 (2500 1500);
DOT 1 (2500 1550);
DOT 1 (2500 1600);
DOT 1 (2500 1650);
DOT 1 (2500 1700);
DOT 1 (2500 1750);
DOT 1 (2500 1800);
DOT 1 (2500 1850);
DOT 1 (2500 1900);
DOT 1 (2500 1950);
DOT 1 (2500 2000);
DOT 1 (2500 2050);
DOT 1 (2500 2100);
DOT 1 (2500 2150);
DOT 1 (2500 2200);
DOT 1 (2500 2300);
DOT 1 (2500 2250);
DOT 1 (2500 2350);
DOT 1 (2500 2400);
DOT 1 (2500 2500);
DOT 1 (2500 2550);
DOT 1 (2500 2600);
DOT 1 (2500 2650);
DOT 1 (2500 2700);
DOT 1 (2500 2750);
DOT 1 (2500 2800);
DOT 1 (2500 2850);
DOT 1 (2500 2900);
DOT 1 (2500 2950);
DOT 1 (2500 3000);
DOT 1 (2500 3050);
DOT 1 (2500 3100);
DOT 1 (2500 3150);
DOT 1 (2500 3200);
DOT 1 (2500 3250);
DOT 1 (2500 3300);
DOT 1 (2500 3350);
DOT 1 (2500 3450);
DOT 1 (2500 3600);
DOT 1 (2500 3650);
DOT 1 (2500 3700);
DOT 1 (1100 3750);
DOT 1 (2500 3750);
DOT 1 (1100 2800);
DOT 1 (-4650 1500);
DOT 1 (-700 2750);
DOT 1 (2500 3400);
DOT 1 (1100 2750);
DOT 1 (2500 2450);
DOT 1 (1100 2100);
DOT 1 (-700 1850);
DOT 1 (-3300 1750);
DOT 1 (-3300 1850);
DOT 1 (-700 2000);
DOT 1 (-700 1950);
FORCENOTE
PLACE CAP NEAR DIMM CONNECTOR
(-5301 948) 0;
DISPLAY LEFT (-5301 948);
DISPLAY 1.595745 (-5301 948);
PAINT PURPLE (-5301 948);
FORCENOTE
SMBUS ADDR: 0XA8
(-5267 687) 0;
DISPLAY LEFT (-5267 687);
DISPLAY 1.574468 (-5267 687);
PAINT PURPLE (-5267 687);
QUIT
